FILE_TYPE = MACRO_DRAWING;
SET COLOR_WIRE YELLOW;
SET COLOR_PROP MONO;
SET COLOR_DOT WHITE;
SET COLOR_ARC YELLOW;
SET COLOR_BODY GREEN;
SET COLOR_NOTE MONO;
SET PROP_DISPLAY VALUE;
SET PAGE_NUMBER P197;
FORCEADD CAP..1
R 1
(-4275 1450);
FORCEPROP 1 LASTPIN (-4375 1450) $PN 1
J 0
(-4405 1460);
DISPLAY 0.617021 (-4405 1460);
PAINT MONO (-4405 1460);
FORCEPROP 1 LAST TOLERANCE 5%
J 0
(-4425 1225);
DISPLAY 0.617021 (-4425 1225);
PAINT SKYBLUE (-4425 1225);
FORCEPROP 1 LAST VOLTAGE 50V
J 0
(-4425 1275);
DISPLAY 0.617021 (-4425 1275);
PAINT SKYBLUE (-4425 1275);
FORCEPROP 1 LAST VALUE 47.0PF
J 0
(-4425 1325);
DISPLAY 0.617021 (-4425 1325);
PAINT SKYBLUE (-4425 1325);
FORCEPROP 1 LAST LOCATION C12W2
J 0
(-4425 1375);
DISPLAY 0.617021 (-4425 1375);
PAINT AQUA (-4425 1375);
FORCEPROP 1 LAST PACK_TYPE 0402LF
J 0
(-4250 1275);
DISPLAY 0.617021 (-4250 1275);
PAINT SKYBLUE (-4250 1275);
FORCEPROP 1 LAST PART_NUMBER A36095-025
J 0
(-4250 1325);
DISPLAY 0.617021 (-4250 1325);
PAINT BLUE (-4250 1325);
FORCEPROP 1 LAST MATERIAL COG
J 0
(-4250 1375);
DISPLAY 0.617021 (-4250 1375);
PAINT SKYBLUE (-4250 1375);
FORCEPROP 1 LASTPIN (-4175 1450) $PN 2
J 0
(-4155 1460);
DISPLAY 0.617021 (-4155 1460);
PAINT MONO (-4155 1460);
FORCEPROP 2 LAST ROOM BMC_VOLT_MONITOR
R 1
J 0
(-4425 1500);
DISPLAY 1.021277 (-4425 1500);
PAINT ORANGE (-4425 1500);
DISPLAY INVISIBLE (-4425 1500);
FORCEPROP 2 LAST SEC 1
R 1
J 0
(-4475 1500);
DISPLAY 0.936170 (-4475 1500);
PAINT MONO (-4475 1500);
DISPLAY INVISIBLE (-4475 1500);
FORCEPROP 2 LAST SEC_TYPE 0402LF
R 1
J 0
(-4475 1500);
PAINT MONO (-4475 1500);
DISPLAY INVISIBLE (-4475 1500);
FORCEPROP 2 LAST CDS_LIB mstr_discrete
R 1
J 0
(-4275 1450);
DISPLAY 1.361702 (-4275 1450);
PAINT ORANGE (-4275 1450);
DISPLAY INVISIBLE (-4275 1450);
FORCEPROP 2 LAST BOM_COST SM_HM
R 1
J 0
(-4475 1500);
DISPLAY 1.021277 (-4475 1500);
PAINT ORANGE (-4475 1500);
DISPLAY INVISIBLE (-4475 1500);
FORCEPROP 2 LAST CDS_LOCATION C12W2
R 1
J 0
(-4375 1500);
DISPLAY 0.617021 (-4375 1500);
PAINT AQUA (-4375 1500);
DISPLAY INVISIBLE (-4375 1500);
FORCEPROP 0 LAST CDS_SEC 1
R 1
J 0
(-4400 1400);
PAINT MONO (-4400 1400);
DISPLAY INVISIBLE (-4400 1400);
FORCEPROP 1 LAST PATH I1
R 1
J 0
(-4425 1500);
DISPLAY 0.978723 (-4425 1500);
PAINT WHITE (-4425 1500);
DISPLAY INVISIBLE (-4425 1500);
FORCEADD 665KR5B-1-GP..1
(-4475 4125);
FORCEPROP 0 LAST CONFIG 064.1003F.M001
J 0
(-4450 4200);
DISPLAY 0.638298 (-4450 4200);
PAINT BROWN (-4450 4200);
DISPLAY BOTH (-4450 4200);
FORCEPROP 0 LAST NEW_VALUE 100K OHM
J 0
(-4450 4150);
DISPLAY 0.638298 (-4450 4150);
PAINT BROWN (-4450 4150);
DISPLAY BOTH (-4450 4150);
FORCEPROP 1 LAST LOCATION R12W1
J 0
(-4450 4255);
DISPLAY 0.617021 (-4450 4255);
PAINT GREEN (-4450 4255);
FORCEPROP 2 LAST PACK_SIZE AT0805
J 0
(-4450 4000);
DISPLAY 0.638298 (-4450 4000);
PAINT GREEN (-4450 4000);
FORCEPROP 2 LAST RATED 1/8W
J 0
(-4450 4050);
DISPLAY 0.638298 (-4450 4050);
PAINT GREEN (-4450 4050);
FORCEPROP 2 LAST TOLERANCE 0.1%
J 0
(-4450 4100);
DISPLAY 0.638298 (-4450 4100);
PAINT GREEN (-4450 4100);
FORCEPROP 1 LAST PATH I101
J 0
(-4475 4125);
DISPLAY 0.617021 (-4475 4125);
PAINT GREEN (-4475 4125);
DISPLAY INVISIBLE (-4475 4125);
FORCEPROP 1 LAST CDS_LMAN_SYM_OUTLINE -50,75,50,-75
J 0
(-4475 4125);
DISPLAY 0.468085 (-4475 4125);
PAINT GREEN (-4475 4125);
DISPLAY INVISIBLE (-4475 4125);
FORCEPROP 2 LAST CDS_LIB w_hdl
J 0
(-4475 4125);
PAINT MONO (-4475 4125);
DISPLAY INVISIBLE (-4475 4125);
FORCEPROP 1 LAST PART_NUMBER 064.6653F.M001
J 0
(-4475 4125);
DISPLAY 0.617021 (-4475 4125);
PAINT GREEN (-4475 4125);
DISPLAY INVISIBLE (-4475 4125);
FORCEPROP 1 LAST PACK_TYPE SMD-RG3
J 0
(-4475 4125);
DISPLAY 0.617021 (-4475 4125);
PAINT GREEN (-4475 4125);
DISPLAY INVISIBLE (-4475 4125);
FORCEPROP 0 LAST ATTRIBUTE 665K OHM
J 0
(-4450 4150);
DISPLAY 0.638298 (-4450 4150);
PAINT GREEN (-4450 4150);
DISPLAY INVISIBLE (-4450 4150);
FORCEPROP 1 LAST VALUE 665KR5B-1-GP
J 0
(-4450 4200);
DISPLAY 0.617021 (-4450 4200);
PAINT GREEN (-4450 4200);
DISPLAY INVISIBLE (-4450 4200);
FORCEADD 665KR2B-GP..1
R 1
(-4250 1700);
FORCEPROP 2 LASTPIN (-4375 1700) $PN 1
J 2
(-4385 1710);
DISPLAY 0.808511 (-4385 1710);
PAINT ORANGE (-4385 1710);
FORCEPROP 2 LAST TOLERANCE 0.1%
J 0
(-4175 1650);
DISPLAY 0.638298 (-4175 1650);
PAINT GREEN (-4175 1650);
FORCEPROP 2 LAST PACK_SIZE 0402
J 0
(-4175 1600);
DISPLAY 0.638298 (-4175 1600);
PAINT GREEN (-4175 1600);
FORCEPROP 2 LAST RATED 1/16W
J 0
(-4175 1550);
DISPLAY 0.638298 (-4175 1550);
PAINT GREEN (-4175 1550);
FORCEPROP 1 LAST VALUE 665KR2B-GP
J 0
(-4425 1600);
DISPLAY 0.617021 (-4425 1600);
PAINT GREEN (-4425 1600);
FORCEPROP 2 LAST ATTRIBUTE 665KOHM
J 0
(-4425 1550);
DISPLAY 0.638298 (-4425 1550);
PAINT GREEN (-4425 1550);
FORCEPROP 0 LAST POP NOPOP
J 0
(-4325 1725);
DISPLAY 0.638298 (-4325 1725);
PAINT RED (-4325 1725);
FORCEPROP 1 LAST LOCATION R12W10
J 0
(-4425 1650);
DISPLAY 0.617021 (-4425 1650);
PAINT GREEN (-4425 1650);
FORCEPROP 2 LASTPIN (-4125 1700) $PN 2
J 0
(-4115 1710);
DISPLAY 0.808511 (-4115 1710);
PAINT ORANGE (-4115 1710);
FORCEPROP 1 LAST CDS_LMAN_SYM_OUTLINE -50,75,50,-75
R 1
J 0
(-4250 1700);
DISPLAY 0.468085 (-4250 1700);
PAINT GREEN (-4250 1700);
DISPLAY INVISIBLE (-4250 1700);
FORCEPROP 2 LAST CDS_LIB w_hdl
R 1
J 0
(-4250 1700);
DISPLAY INVISIBLE (-4250 1700);
FORCEPROP 1 LAST PART_NUMBER 064.6653D.06DD
R 1
J 0
(-4250 1700);
DISPLAY 0.617021 (-4250 1700);
PAINT GREEN (-4250 1700);
DISPLAY INVISIBLE (-4250 1700);
FORCEPROP 2 LAST SEC_TYPE SMD-RG2
J 0
(-4150 1775);
DISPLAY 1.021277 (-4150 1775);
PAINT ORANGE (-4150 1775);
DISPLAY INVISIBLE (-4150 1775);
FORCEPROP 2 LAST SEC 1
J 0
(-4150 1775);
DISPLAY 0.680851 (-4150 1775);
PAINT MONO (-4150 1775);
DISPLAY INVISIBLE (-4150 1775);
FORCEPROP 1 LAST PACK_TYPE SMD-RG2
R 1
J 0
(-4250 1700);
DISPLAY 0.617021 (-4250 1700);
PAINT GREEN (-4250 1700);
DISPLAY INVISIBLE (-4250 1700);
FORCEPROP 1 LAST PATH I109
R 1
J 0
(-4250 1700);
DISPLAY 0.617021 (-4250 1700);
PAINT GREEN (-4250 1700);
DISPLAY INVISIBLE (-4250 1700);
FORCEADD 665KR2B-GP..1
R 1
(-1700 1700);
FORCEPROP 1 LAST VALUE 665KR2B-GP
J 0
(-1875 1550);
DISPLAY 0.617021 (-1875 1550);
PAINT GREEN (-1875 1550);
FORCEPROP 2 LAST ATTRIBUTE 665KOHM
J 0
(-1875 1600);
DISPLAY 0.638298 (-1875 1600);
PAINT GREEN (-1875 1600);
FORCEPROP 1 LAST LOCATION R12W20
J 0
(-1875 1650);
DISPLAY 0.617021 (-1875 1650);
PAINT GREEN (-1875 1650);
FORCEPROP 0 LAST POP NOPOP
J 0
(-1775 1725);
DISPLAY 0.638298 (-1775 1725);
PAINT RED (-1775 1725);
FORCEPROP 2 LASTPIN (-1825 1700) $PN 1
J 2
(-1835 1710);
DISPLAY 0.808511 (-1835 1710);
PAINT ORANGE (-1835 1710);
FORCEPROP 2 LAST RATED 1/16W
J 0
(-1625 1550);
DISPLAY 0.638298 (-1625 1550);
PAINT GREEN (-1625 1550);
FORCEPROP 2 LAST TOLERANCE 0.1%
J 0
(-1625 1650);
DISPLAY 0.638298 (-1625 1650);
PAINT GREEN (-1625 1650);
FORCEPROP 2 LAST PACK_SIZE 0402
J 0
(-1625 1600);
DISPLAY 0.638298 (-1625 1600);
PAINT GREEN (-1625 1600);
FORCEPROP 2 LASTPIN (-1575 1700) $PN 2
J 0
(-1565 1710);
DISPLAY 0.808511 (-1565 1710);
PAINT ORANGE (-1565 1710);
FORCEPROP 1 LAST PATH I110
R 1
J 0
(-1700 1700);
DISPLAY 0.617021 (-1700 1700);
PAINT GREEN (-1700 1700);
DISPLAY INVISIBLE (-1700 1700);
FORCEPROP 1 LAST CDS_LMAN_SYM_OUTLINE -50,75,50,-75
R 1
J 0
(-1700 1700);
DISPLAY 0.468085 (-1700 1700);
PAINT GREEN (-1700 1700);
DISPLAY INVISIBLE (-1700 1700);
FORCEPROP 2 LAST CDS_LIB w_hdl
R 1
J 0
(-1700 1700);
DISPLAY INVISIBLE (-1700 1700);
FORCEPROP 1 LAST PART_NUMBER 064.6653D.06DD
R 1
J 0
(-1700 1700);
DISPLAY 0.617021 (-1700 1700);
PAINT GREEN (-1700 1700);
DISPLAY INVISIBLE (-1700 1700);
FORCEPROP 2 LAST SEC_TYPE SMD-RG2
J 0
(-1600 1775);
DISPLAY 1.021277 (-1600 1775);
PAINT ORANGE (-1600 1775);
DISPLAY INVISIBLE (-1600 1775);
FORCEPROP 2 LAST SEC 1
J 0
(-1600 1775);
DISPLAY 0.680851 (-1600 1775);
PAINT MONO (-1600 1775);
DISPLAY INVISIBLE (-1600 1775);
FORCEPROP 1 LAST PACK_TYPE SMD-RG2
R 1
J 0
(-1700 1700);
DISPLAY 0.617021 (-1700 1700);
PAINT GREEN (-1700 1700);
DISPLAY INVISIBLE (-1700 1700);
FORCEADD 665KR2B-GP..1
R 1
(-4250 3800);
FORCEPROP 2 LASTPIN (-4125 3800) $PN 2
J 0
(-4115 3810);
DISPLAY 0.808511 (-4115 3810);
PAINT ORANGE (-4115 3810);
FORCEPROP 2 LAST TOLERANCE 0.1%
J 0
(-4175 3750);
DISPLAY 0.638298 (-4175 3750);
PAINT GREEN (-4175 3750);
FORCEPROP 2 LASTPIN (-4375 3800) $PN 1
J 2
(-4385 3810);
DISPLAY 0.808511 (-4385 3810);
PAINT ORANGE (-4385 3810);
FORCEPROP 2 LAST PACK_SIZE 0402
J 0
(-4175 3700);
DISPLAY 0.638298 (-4175 3700);
PAINT GREEN (-4175 3700);
FORCEPROP 2 LAST RATED 1/16W
J 0
(-4175 3650);
DISPLAY 0.638298 (-4175 3650);
PAINT GREEN (-4175 3650);
FORCEPROP 2 LAST ATTRIBUTE 665KOHM
J 0
(-4425 3650);
DISPLAY 0.638298 (-4425 3650);
PAINT GREEN (-4425 3650);
FORCEPROP 1 LAST VALUE 665KR2B-GP
J 0
(-4425 3700);
DISPLAY 0.617021 (-4425 3700);
PAINT GREEN (-4425 3700);
FORCEPROP 1 LAST LOCATION R12W5
J 0
(-4425 3750);
DISPLAY 0.617021 (-4425 3750);
PAINT GREEN (-4425 3750);
FORCEPROP 0 LAST POP NOPOP
J 0
(-4325 3825);
DISPLAY 0.638298 (-4325 3825);
PAINT RED (-4325 3825);
FORCEPROP 1 LAST PATH I111
R 1
J 0
(-4250 3800);
DISPLAY 0.617021 (-4250 3800);
PAINT GREEN (-4250 3800);
DISPLAY INVISIBLE (-4250 3800);
FORCEPROP 1 LAST PACK_TYPE SMD-RG2
R 1
J 0
(-4250 3800);
DISPLAY 0.617021 (-4250 3800);
PAINT GREEN (-4250 3800);
DISPLAY INVISIBLE (-4250 3800);
FORCEPROP 2 LAST SEC 1
J 0
(-4150 3875);
DISPLAY 0.680851 (-4150 3875);
PAINT MONO (-4150 3875);
DISPLAY INVISIBLE (-4150 3875);
FORCEPROP 2 LAST SEC_TYPE SMD-RG2
J 0
(-4150 3875);
DISPLAY 1.021277 (-4150 3875);
PAINT ORANGE (-4150 3875);
DISPLAY INVISIBLE (-4150 3875);
FORCEPROP 1 LAST PART_NUMBER 064.6653D.06DD
R 1
J 0
(-4250 3800);
DISPLAY 0.617021 (-4250 3800);
PAINT GREEN (-4250 3800);
DISPLAY INVISIBLE (-4250 3800);
FORCEPROP 2 LAST CDS_LIB w_hdl
R 1
J 0
(-4250 3800);
DISPLAY INVISIBLE (-4250 3800);
FORCEPROP 1 LAST CDS_LMAN_SYM_OUTLINE -50,75,50,-75
R 1
J 0
(-4250 3800);
DISPLAY 0.468085 (-4250 3800);
PAINT GREEN (-4250 3800);
DISPLAY INVISIBLE (-4250 3800);
FORCEADD 665KR2B-GP..1
R 1
(-1700 3800);
FORCEPROP 2 LAST PACK_SIZE 0402
J 0
(-1650 3700);
DISPLAY 0.638298 (-1650 3700);
PAINT GREEN (-1650 3700);
FORCEPROP 1 LAST VALUE 665KR2B-GP
J 0
(-1875 3700);
DISPLAY 0.617021 (-1875 3700);
PAINT GREEN (-1875 3700);
FORCEPROP 2 LAST ATTRIBUTE 665KOHM
J 0
(-1875 3650);
DISPLAY 0.638298 (-1875 3650);
PAINT GREEN (-1875 3650);
FORCEPROP 2 LASTPIN (-1825 3800) $PN 1
J 2
(-1835 3810);
DISPLAY 0.808511 (-1835 3810);
PAINT ORANGE (-1835 3810);
FORCEPROP 1 LAST LOCATION R12W15
J 0
(-1875 3750);
DISPLAY 0.617021 (-1875 3750);
PAINT GREEN (-1875 3750);
FORCEPROP 0 LAST POP NOPOP
J 0
(-1775 3825);
DISPLAY 0.638298 (-1775 3825);
PAINT RED (-1775 3825);
FORCEPROP 2 LAST RATED 1/16W
J 0
(-1650 3650);
DISPLAY 0.638298 (-1650 3650);
PAINT GREEN (-1650 3650);
FORCEPROP 2 LAST TOLERANCE 0.1%
J 0
(-1650 3750);
DISPLAY 0.638298 (-1650 3750);
PAINT GREEN (-1650 3750);
FORCEPROP 2 LASTPIN (-1575 3800) $PN 2
J 0
(-1565 3810);
DISPLAY 0.808511 (-1565 3810);
PAINT ORANGE (-1565 3810);
FORCEPROP 1 LAST PACK_TYPE SMD-RG2
R 1
J 0
(-1700 3800);
DISPLAY 0.617021 (-1700 3800);
PAINT GREEN (-1700 3800);
DISPLAY INVISIBLE (-1700 3800);
FORCEPROP 2 LAST SEC 1
J 0
(-1600 3875);
DISPLAY 0.680851 (-1600 3875);
PAINT MONO (-1600 3875);
DISPLAY INVISIBLE (-1600 3875);
FORCEPROP 2 LAST SEC_TYPE SMD-RG2
J 0
(-1600 3875);
DISPLAY 1.021277 (-1600 3875);
PAINT ORANGE (-1600 3875);
DISPLAY INVISIBLE (-1600 3875);
FORCEPROP 1 LAST PART_NUMBER 064.6653D.06DD
R 1
J 0
(-1700 3800);
DISPLAY 0.617021 (-1700 3800);
PAINT GREEN (-1700 3800);
DISPLAY INVISIBLE (-1700 3800);
FORCEPROP 2 LAST CDS_LIB w_hdl
R 1
J 0
(-1700 3800);
DISPLAY INVISIBLE (-1700 3800);
FORCEPROP 1 LAST CDS_LMAN_SYM_OUTLINE -50,75,50,-75
R 1
J 0
(-1700 3800);
DISPLAY 0.468085 (-1700 3800);
PAINT GREEN (-1700 3800);
DISPLAY INVISIBLE (-1700 3800);
FORCEPROP 1 LAST PATH I112
R 1
J 0
(-1700 3800);
DISPLAY 0.617021 (-1700 3800);
PAINT GREEN (-1700 3800);
DISPLAY INVISIBLE (-1700 3800);
FORCEADD 4D02R2F-GP..1
R 1
(-4250 2450);
FORCEPROP 2 LAST PACK_SIZE 0402
J 0
(-3875 2500);
DISPLAY 0.638298 (-3875 2500);
PAINT GREEN (-3875 2500);
FORCEPROP 2 LAST ATTRIBUTE 4.02OHM
J 0
(-4100 2550);
DISPLAY 0.638298 (-4100 2550);
PAINT GREEN (-4100 2550);
FORCEPROP 2 LAST TOLERANCE 1%
J 0
(-3875 2550);
DISPLAY 0.638298 (-3875 2550);
PAINT GREEN (-3875 2550);
FORCEPROP 2 LAST RATED 1/16W
J 0
(-4100 2500);
DISPLAY 0.638298 (-4100 2500);
PAINT GREEN (-4100 2500);
FORCEPROP 1 LAST VALUE 4D02R2F-GP
J 0
(-4375 2500);
DISPLAY 0.617021 (-4375 2500);
PAINT GREEN (-4375 2500);
FORCEPROP 1 LAST LOCATION R12W8
J 0
(-4375 2550);
DISPLAY 0.617021 (-4375 2550);
PAINT GREEN (-4375 2550);
FORCEPROP 2 LASTPIN (-4375 2450) $PN 1
J 2
(-4385 2460);
DISPLAY 0.808511 (-4385 2460);
PAINT ORANGE (-4385 2460);
FORCEPROP 2 LASTPIN (-4125 2450) $PN 2
J 0
(-4115 2460);
DISPLAY 0.808511 (-4115 2460);
PAINT ORANGE (-4115 2460);
FORCEPROP 1 LAST PART_NUMBER 64.4R025.6DL
R 1
J 0
(-4250 2450);
DISPLAY 0.617021 (-4250 2450);
PAINT GREEN (-4250 2450);
DISPLAY INVISIBLE (-4250 2450);
FORCEPROP 2 LAST CDS_LIB w_hdl
R 1
J 0
(-4250 2450);
DISPLAY INVISIBLE (-4250 2450);
FORCEPROP 1 LAST CDS_LMAN_SYM_OUTLINE -50,75,50,-75
R 1
J 0
(-4250 2450);
DISPLAY 0.468085 (-4250 2450);
PAINT GREEN (-4250 2450);
DISPLAY INVISIBLE (-4250 2450);
FORCEPROP 2 LAST SEC_TYPE SMD-RG2
J 0
(-4125 2500);
DISPLAY 1.021277 (-4125 2500);
PAINT ORANGE (-4125 2500);
DISPLAY INVISIBLE (-4125 2500);
FORCEPROP 2 LAST SEC 1
J 0
(-4125 2500);
DISPLAY 0.680851 (-4125 2500);
PAINT MONO (-4125 2500);
DISPLAY INVISIBLE (-4125 2500);
FORCEPROP 1 LAST PACK_TYPE SMD-RG2
R 1
J 0
(-4250 2450);
DISPLAY 0.617021 (-4250 2450);
PAINT GREEN (-4250 2450);
DISPLAY INVISIBLE (-4250 2450);
FORCEPROP 1 LAST PATH I113
R 1
J 0
(-4250 2450);
DISPLAY 0.617021 (-4250 2450);
PAINT GREEN (-4250 2450);
DISPLAY INVISIBLE (-4250 2450);
FORCEADD 4D02R2F-GP..1
R 1
(-1700 2450);
FORCEPROP 1 LAST LOCATION R12W18
J 0
(-1825 2550);
DISPLAY 0.617021 (-1825 2550);
PAINT GREEN (-1825 2550);
FORCEPROP 2 LAST PACK_SIZE 0402
J 0
(-1325 2500);
DISPLAY 0.638298 (-1325 2500);
PAINT GREEN (-1325 2500);
FORCEPROP 2 LAST TOLERANCE 1%
J 0
(-1325 2550);
DISPLAY 0.638298 (-1325 2550);
PAINT GREEN (-1325 2550);
FORCEPROP 2 LAST ATTRIBUTE 4.02OHM
J 0
(-1550 2550);
DISPLAY 0.638298 (-1550 2550);
PAINT GREEN (-1550 2550);
FORCEPROP 2 LAST RATED 1/16W
J 0
(-1550 2500);
DISPLAY 0.638298 (-1550 2500);
PAINT GREEN (-1550 2500);
FORCEPROP 1 LAST VALUE 4D02R2F-GP
J 0
(-1825 2500);
DISPLAY 0.617021 (-1825 2500);
PAINT GREEN (-1825 2500);
FORCEPROP 2 LASTPIN (-1575 2450) $PN 2
J 0
(-1565 2460);
DISPLAY 0.808511 (-1565 2460);
PAINT ORANGE (-1565 2460);
FORCEPROP 2 LASTPIN (-1825 2450) $PN 1
J 2
(-1835 2460);
DISPLAY 0.808511 (-1835 2460);
PAINT ORANGE (-1835 2460);
FORCEPROP 1 LAST PACK_TYPE SMD-RG2
R 1
J 0
(-1700 2450);
DISPLAY 0.617021 (-1700 2450);
PAINT GREEN (-1700 2450);
DISPLAY INVISIBLE (-1700 2450);
FORCEPROP 2 LAST SEC 1
J 0
(-1575 2500);
DISPLAY 0.680851 (-1575 2500);
PAINT MONO (-1575 2500);
DISPLAY INVISIBLE (-1575 2500);
FORCEPROP 2 LAST SEC_TYPE SMD-RG2
J 0
(-1575 2500);
DISPLAY 1.021277 (-1575 2500);
PAINT ORANGE (-1575 2500);
DISPLAY INVISIBLE (-1575 2500);
FORCEPROP 1 LAST CDS_LMAN_SYM_OUTLINE -50,75,50,-75
R 1
J 0
(-1700 2450);
DISPLAY 0.468085 (-1700 2450);
PAINT GREEN (-1700 2450);
DISPLAY INVISIBLE (-1700 2450);
FORCEPROP 2 LAST CDS_LIB w_hdl
R 1
J 0
(-1700 2450);
DISPLAY INVISIBLE (-1700 2450);
FORCEPROP 1 LAST PART_NUMBER 64.4R025.6DL
R 1
J 0
(-1700 2450);
DISPLAY 0.617021 (-1700 2450);
PAINT GREEN (-1700 2450);
DISPLAY INVISIBLE (-1700 2450);
FORCEPROP 1 LAST PATH I114
R 1
J 0
(-1700 2450);
DISPLAY 0.617021 (-1700 2450);
PAINT GREEN (-1700 2450);
DISPLAY INVISIBLE (-1700 2450);
FORCEADD 4D02R2F-GP..1
R 1
(-4250 4550);
FORCEPROP 2 LAST ATTRIBUTE 4.02OHM
J 0
(-4100 4650);
DISPLAY 0.638298 (-4100 4650);
PAINT GREEN (-4100 4650);
FORCEPROP 2 LAST RATED 1/16W
J 0
(-4100 4600);
DISPLAY 0.638298 (-4100 4600);
PAINT GREEN (-4100 4600);
FORCEPROP 2 LASTPIN (-4125 4550) $PN 2
J 0
(-4115 4560);
DISPLAY 0.808511 (-4115 4560);
PAINT ORANGE (-4115 4560);
FORCEPROP 1 LAST LOCATION R12W3
J 0
(-4375 4650);
DISPLAY 0.617021 (-4375 4650);
PAINT GREEN (-4375 4650);
FORCEPROP 2 LASTPIN (-4375 4550) $PN 1
J 2
(-4385 4560);
DISPLAY 0.808511 (-4385 4560);
PAINT ORANGE (-4385 4560);
FORCEPROP 1 LAST VALUE 4D02R2F-GP
J 0
(-4375 4600);
DISPLAY 0.617021 (-4375 4600);
PAINT GREEN (-4375 4600);
FORCEPROP 2 LAST PACK_SIZE 0402
J 0
(-3875 4600);
DISPLAY 0.638298 (-3875 4600);
PAINT GREEN (-3875 4600);
FORCEPROP 2 LAST TOLERANCE 1%
J 0
(-3875 4650);
DISPLAY 0.638298 (-3875 4650);
PAINT GREEN (-3875 4650);
FORCEPROP 1 LAST PART_NUMBER 64.4R025.6DL
R 1
J 0
(-4250 4550);
DISPLAY 0.617021 (-4250 4550);
PAINT GREEN (-4250 4550);
DISPLAY INVISIBLE (-4250 4550);
FORCEPROP 2 LAST CDS_LIB w_hdl
R 1
J 0
(-4250 4550);
DISPLAY INVISIBLE (-4250 4550);
FORCEPROP 1 LAST CDS_LMAN_SYM_OUTLINE -50,75,50,-75
R 1
J 0
(-4250 4550);
DISPLAY 0.468085 (-4250 4550);
PAINT GREEN (-4250 4550);
DISPLAY INVISIBLE (-4250 4550);
FORCEPROP 2 LAST SEC_TYPE SMD-RG2
J 0
(-4125 4600);
DISPLAY 1.021277 (-4125 4600);
PAINT ORANGE (-4125 4600);
DISPLAY INVISIBLE (-4125 4600);
FORCEPROP 2 LAST SEC 1
J 0
(-4125 4600);
DISPLAY 0.680851 (-4125 4600);
PAINT MONO (-4125 4600);
DISPLAY INVISIBLE (-4125 4600);
FORCEPROP 1 LAST PACK_TYPE SMD-RG2
R 1
J 0
(-4250 4550);
DISPLAY 0.617021 (-4250 4550);
PAINT GREEN (-4250 4550);
DISPLAY INVISIBLE (-4250 4550);
FORCEPROP 1 LAST PATH I115
R 1
J 0
(-4250 4550);
DISPLAY 0.617021 (-4250 4550);
PAINT GREEN (-4250 4550);
DISPLAY INVISIBLE (-4250 4550);
FORCEADD 4D02R2F-GP..1
R 1
(-1700 4550);
FORCEPROP 2 LAST PACK_SIZE 0402
J 0
(-1325 4600);
DISPLAY 0.638298 (-1325 4600);
PAINT GREEN (-1325 4600);
FORCEPROP 2 LAST TOLERANCE 1%
J 0
(-1325 4650);
DISPLAY 0.638298 (-1325 4650);
PAINT GREEN (-1325 4650);
FORCEPROP 2 LASTPIN (-1825 4550) $PN 1
J 2
(-1835 4560);
DISPLAY 0.808511 (-1835 4560);
PAINT ORANGE (-1835 4560);
FORCEPROP 1 LAST VALUE 4D02R2F-GP
J 0
(-1825 4600);
DISPLAY 0.617021 (-1825 4600);
PAINT GREEN (-1825 4600);
FORCEPROP 1 LAST LOCATION R12W13
J 0
(-1825 4650);
DISPLAY 0.617021 (-1825 4650);
PAINT GREEN (-1825 4650);
FORCEPROP 2 LASTPIN (-1575 4550) $PN 2
J 0
(-1565 4560);
DISPLAY 0.808511 (-1565 4560);
PAINT ORANGE (-1565 4560);
FORCEPROP 2 LAST RATED 1/16W
J 0
(-1550 4600);
DISPLAY 0.638298 (-1550 4600);
PAINT GREEN (-1550 4600);
FORCEPROP 2 LAST ATTRIBUTE 4.02OHM
J 0
(-1550 4650);
DISPLAY 0.638298 (-1550 4650);
PAINT GREEN (-1550 4650);
FORCEPROP 1 LAST PATH I116
R 1
J 0
(-1700 4550);
DISPLAY 0.617021 (-1700 4550);
PAINT GREEN (-1700 4550);
DISPLAY INVISIBLE (-1700 4550);
FORCEPROP 1 LAST PART_NUMBER 64.4R025.6DL
R 1
J 0
(-1700 4550);
DISPLAY 0.617021 (-1700 4550);
PAINT GREEN (-1700 4550);
DISPLAY INVISIBLE (-1700 4550);
FORCEPROP 2 LAST CDS_LIB w_hdl
R 1
J 0
(-1700 4550);
DISPLAY INVISIBLE (-1700 4550);
FORCEPROP 1 LAST CDS_LMAN_SYM_OUTLINE -50,75,50,-75
R 1
J 0
(-1700 4550);
DISPLAY 0.468085 (-1700 4550);
PAINT GREEN (-1700 4550);
DISPLAY INVISIBLE (-1700 4550);
FORCEPROP 2 LAST SEC_TYPE SMD-RG2
J 0
(-1575 4600);
DISPLAY 1.021277 (-1575 4600);
PAINT ORANGE (-1575 4600);
DISPLAY INVISIBLE (-1575 4600);
FORCEPROP 2 LAST SEC 1
J 0
(-1575 4600);
DISPLAY 0.680851 (-1575 4600);
PAINT MONO (-1575 4600);
DISPLAY INVISIBLE (-1575 4600);
FORCEPROP 1 LAST PACK_TYPE SMD-RG2
R 1
J 0
(-1700 4550);
DISPLAY 0.617021 (-1700 4550);
PAINT GREEN (-1700 4550);
DISPLAY INVISIBLE (-1700 4550);
FORCEADD 665KR5B-1-GP..1
(-4025 4125);
FORCEPROP 0 LAST NEW_VALUE 100K OHM
J 0
(-4000 4150);
DISPLAY 0.638298 (-4000 4150);
PAINT BROWN (-4000 4150);
DISPLAY BOTH (-4000 4150);
FORCEPROP 1 LAST LOCATION R12W2
J 0
(-4000 4255);
DISPLAY 0.617021 (-4000 4255);
PAINT GREEN (-4000 4255);
FORCEPROP 2 LAST TOLERANCE 0.1%
J 0
(-4000 4100);
DISPLAY 0.638298 (-4000 4100);
PAINT GREEN (-4000 4100);
FORCEPROP 2 LAST RATED 1/8W
J 0
(-4000 4050);
DISPLAY 0.638298 (-4000 4050);
PAINT GREEN (-4000 4050);
FORCEPROP 2 LAST PACK_SIZE AT0805
J 0
(-4000 4000);
DISPLAY 0.638298 (-4000 4000);
PAINT GREEN (-4000 4000);
FORCEPROP 0 LAST CONFIG 064.1003F.M001
J 0
(-4000 4200);
DISPLAY 0.638298 (-4000 4200);
PAINT BROWN (-4000 4200);
DISPLAY BOTH (-4000 4200);
FORCEPROP 1 LAST PATH I117
J 0
(-4025 4125);
DISPLAY 0.617021 (-4025 4125);
PAINT GREEN (-4025 4125);
DISPLAY INVISIBLE (-4025 4125);
FORCEPROP 1 LAST VALUE 665KR5B-1-GP
J 0
(-4000 4200);
DISPLAY 0.617021 (-4000 4200);
PAINT GREEN (-4000 4200);
DISPLAY INVISIBLE (-4000 4200);
FORCEPROP 0 LAST ATTRIBUTE 665K OHM
J 0
(-4000 4150);
DISPLAY 0.638298 (-4000 4150);
PAINT GREEN (-4000 4150);
DISPLAY INVISIBLE (-4000 4150);
FORCEPROP 1 LAST PACK_TYPE SMD-RG3
J 0
(-4025 4125);
DISPLAY 0.617021 (-4025 4125);
PAINT GREEN (-4025 4125);
DISPLAY INVISIBLE (-4025 4125);
FORCEPROP 1 LAST PART_NUMBER 064.6653F.M001
J 0
(-4025 4125);
DISPLAY 0.617021 (-4025 4125);
PAINT GREEN (-4025 4125);
DISPLAY INVISIBLE (-4025 4125);
FORCEPROP 2 LAST CDS_LIB w_hdl
J 0
(-4025 4125);
PAINT MONO (-4025 4125);
DISPLAY INVISIBLE (-4025 4125);
FORCEPROP 1 LAST CDS_LMAN_SYM_OUTLINE -50,75,50,-75
J 0
(-4025 4125);
DISPLAY 0.468085 (-4025 4125);
PAINT GREEN (-4025 4125);
DISPLAY INVISIBLE (-4025 4125);
FORCEADD 665KR5B-1-GP..1
(-1925 4125);
FORCEPROP 2 LAST PACK_SIZE AT0805
J 0
(-1900 4000);
DISPLAY 0.638298 (-1900 4000);
PAINT GREEN (-1900 4000);
FORCEPROP 2 LAST RATED 1/8W
J 0
(-1900 4050);
DISPLAY 0.638298 (-1900 4050);
PAINT GREEN (-1900 4050);
FORCEPROP 2 LAST TOLERANCE 0.1%
J 0
(-1900 4100);
DISPLAY 0.638298 (-1900 4100);
PAINT GREEN (-1900 4100);
FORCEPROP 1 LAST LOCATION R12W11
J 0
(-1900 4255);
DISPLAY 0.617021 (-1900 4255);
PAINT GREEN (-1900 4255);
FORCEPROP 0 LAST NEW_VALUE 100K OHM
J 0
(-1900 4150);
DISPLAY 0.638298 (-1900 4150);
PAINT BROWN (-1900 4150);
DISPLAY BOTH (-1900 4150);
FORCEPROP 0 LAST CONFIG 064.1003F.M001
J 0
(-1900 4200);
DISPLAY 0.638298 (-1900 4200);
PAINT BROWN (-1900 4200);
DISPLAY BOTH (-1900 4200);
FORCEPROP 1 LAST PATH I118
J 0
(-1925 4125);
DISPLAY 0.617021 (-1925 4125);
PAINT GREEN (-1925 4125);
DISPLAY INVISIBLE (-1925 4125);
FORCEPROP 1 LAST CDS_LMAN_SYM_OUTLINE -50,75,50,-75
J 0
(-1925 4125);
DISPLAY 0.468085 (-1925 4125);
PAINT GREEN (-1925 4125);
DISPLAY INVISIBLE (-1925 4125);
FORCEPROP 2 LAST CDS_LIB w_hdl
J 0
(-1925 4125);
PAINT MONO (-1925 4125);
DISPLAY INVISIBLE (-1925 4125);
FORCEPROP 1 LAST PART_NUMBER 064.6653F.M001
J 0
(-1925 4125);
DISPLAY 0.617021 (-1925 4125);
PAINT GREEN (-1925 4125);
DISPLAY INVISIBLE (-1925 4125);
FORCEPROP 1 LAST PACK_TYPE SMD-RG3
J 0
(-1925 4125);
DISPLAY 0.617021 (-1925 4125);
PAINT GREEN (-1925 4125);
DISPLAY INVISIBLE (-1925 4125);
FORCEPROP 0 LAST ATTRIBUTE 665K OHM
J 0
(-1900 4150);
DISPLAY 0.638298 (-1900 4150);
PAINT GREEN (-1900 4150);
DISPLAY INVISIBLE (-1900 4150);
FORCEPROP 1 LAST VALUE 665KR5B-1-GP
J 0
(-1900 4200);
DISPLAY 0.617021 (-1900 4200);
PAINT GREEN (-1900 4200);
DISPLAY INVISIBLE (-1900 4200);
FORCEADD 665KR5B-1-GP..1
(-1475 4125);
FORCEPROP 1 LAST LOCATION R12W12
J 0
(-1450 4255);
DISPLAY 0.617021 (-1450 4255);
PAINT GREEN (-1450 4255);
FORCEPROP 2 LAST TOLERANCE 0.1%
J 0
(-1450 4100);
DISPLAY 0.638298 (-1450 4100);
PAINT GREEN (-1450 4100);
FORCEPROP 2 LAST RATED 1/8W
J 0
(-1450 4050);
DISPLAY 0.638298 (-1450 4050);
PAINT GREEN (-1450 4050);
FORCEPROP 0 LAST CONFIG 064.1003F.M001
J 0
(-1450 4200);
DISPLAY 0.638298 (-1450 4200);
PAINT BROWN (-1450 4200);
DISPLAY BOTH (-1450 4200);
FORCEPROP 0 LAST NEW_VALUE 100K OHM
J 0
(-1450 4150);
DISPLAY 0.638298 (-1450 4150);
PAINT BROWN (-1450 4150);
DISPLAY BOTH (-1450 4150);
FORCEPROP 2 LAST PACK_SIZE AT0805
J 0
(-1450 4000);
DISPLAY 0.638298 (-1450 4000);
PAINT GREEN (-1450 4000);
FORCEPROP 1 LAST PATH I119
J 0
(-1475 4125);
DISPLAY 0.617021 (-1475 4125);
PAINT GREEN (-1475 4125);
DISPLAY INVISIBLE (-1475 4125);
FORCEPROP 1 LAST VALUE 665KR5B-1-GP
J 0
(-1450 4200);
DISPLAY 0.617021 (-1450 4200);
PAINT GREEN (-1450 4200);
DISPLAY INVISIBLE (-1450 4200);
FORCEPROP 0 LAST ATTRIBUTE 665K OHM
J 0
(-1450 4150);
DISPLAY 0.638298 (-1450 4150);
PAINT GREEN (-1450 4150);
DISPLAY INVISIBLE (-1450 4150);
FORCEPROP 1 LAST PACK_TYPE SMD-RG3
J 0
(-1475 4125);
DISPLAY 0.617021 (-1475 4125);
PAINT GREEN (-1475 4125);
DISPLAY INVISIBLE (-1475 4125);
FORCEPROP 1 LAST PART_NUMBER 064.6653F.M001
J 0
(-1475 4125);
DISPLAY 0.617021 (-1475 4125);
PAINT GREEN (-1475 4125);
DISPLAY INVISIBLE (-1475 4125);
FORCEPROP 2 LAST CDS_LIB w_hdl
J 0
(-1475 4125);
PAINT MONO (-1475 4125);
DISPLAY INVISIBLE (-1475 4125);
FORCEPROP 1 LAST CDS_LMAN_SYM_OUTLINE -50,75,50,-75
J 0
(-1475 4125);
DISPLAY 0.468085 (-1475 4125);
PAINT GREEN (-1475 4125);
DISPLAY INVISIBLE (-1475 4125);
FORCEADD 665KR5B-1-GP..1
(-4475 2025);
FORCEPROP 0 LAST NEW_VALUE 100K OHM
J 0
(-4450 2050);
DISPLAY 0.638298 (-4450 2050);
PAINT BROWN (-4450 2050);
DISPLAY BOTH (-4450 2050);
FORCEPROP 0 LAST CONFIG 064.1003F.M001
J 0
(-4450 2100);
DISPLAY 0.638298 (-4450 2100);
PAINT BROWN (-4450 2100);
DISPLAY BOTH (-4450 2100);
FORCEPROP 2 LAST TOLERANCE 0.1%
J 0
(-4450 2000);
DISPLAY 0.638298 (-4450 2000);
PAINT GREEN (-4450 2000);
FORCEPROP 2 LAST RATED 1/8W
J 0
(-4450 1950);
DISPLAY 0.638298 (-4450 1950);
PAINT GREEN (-4450 1950);
FORCEPROP 2 LAST PACK_SIZE AT0805
J 0
(-4450 1900);
DISPLAY 0.638298 (-4450 1900);
PAINT GREEN (-4450 1900);
FORCEPROP 1 LAST LOCATION R12W6
J 0
(-4450 2155);
DISPLAY 0.617021 (-4450 2155);
PAINT GREEN (-4450 2155);
FORCEPROP 1 LAST PATH I120
J 0
(-4475 2025);
DISPLAY 0.617021 (-4475 2025);
PAINT GREEN (-4475 2025);
DISPLAY INVISIBLE (-4475 2025);
FORCEPROP 1 LAST VALUE 665KR5B-1-GP
J 0
(-4450 2100);
DISPLAY 0.617021 (-4450 2100);
PAINT GREEN (-4450 2100);
DISPLAY INVISIBLE (-4450 2100);
FORCEPROP 0 LAST ATTRIBUTE 665K OHM
J 0
(-4450 2050);
DISPLAY 0.638298 (-4450 2050);
PAINT GREEN (-4450 2050);
DISPLAY INVISIBLE (-4450 2050);
FORCEPROP 1 LAST PACK_TYPE SMD-RG3
J 0
(-4475 2025);
DISPLAY 0.617021 (-4475 2025);
PAINT GREEN (-4475 2025);
DISPLAY INVISIBLE (-4475 2025);
FORCEPROP 1 LAST PART_NUMBER 064.6653F.M001
J 0
(-4475 2025);
DISPLAY 0.617021 (-4475 2025);
PAINT GREEN (-4475 2025);
DISPLAY INVISIBLE (-4475 2025);
FORCEPROP 2 LAST CDS_LIB w_hdl
J 0
(-4475 2025);
PAINT MONO (-4475 2025);
DISPLAY INVISIBLE (-4475 2025);
FORCEPROP 1 LAST CDS_LMAN_SYM_OUTLINE -50,75,50,-75
J 0
(-4475 2025);
DISPLAY 0.468085 (-4475 2025);
PAINT GREEN (-4475 2025);
DISPLAY INVISIBLE (-4475 2025);
FORCEADD 665KR5B-1-GP..1
(-4025 2025);
FORCEPROP 2 LAST PACK_SIZE AT0805
J 0
(-4000 1900);
DISPLAY 0.638298 (-4000 1900);
PAINT GREEN (-4000 1900);
FORCEPROP 0 LAST CONFIG 064.1003F.M001
J 0
(-4000 2100);
DISPLAY 0.638298 (-4000 2100);
PAINT BROWN (-4000 2100);
DISPLAY BOTH (-4000 2100);
FORCEPROP 0 LAST NEW_VALUE 100K OHM
J 0
(-4000 2050);
DISPLAY 0.638298 (-4000 2050);
PAINT BROWN (-4000 2050);
DISPLAY BOTH (-4000 2050);
FORCEPROP 1 LAST LOCATION R12W7
J 0
(-4000 2155);
DISPLAY 0.617021 (-4000 2155);
PAINT GREEN (-4000 2155);
FORCEPROP 2 LAST TOLERANCE 0.1%
J 0
(-4000 2000);
DISPLAY 0.638298 (-4000 2000);
PAINT GREEN (-4000 2000);
FORCEPROP 2 LAST RATED 1/8W
J 0
(-4000 1950);
DISPLAY 0.638298 (-4000 1950);
PAINT GREEN (-4000 1950);
FORCEPROP 1 LAST CDS_LMAN_SYM_OUTLINE -50,75,50,-75
J 0
(-4025 2025);
DISPLAY 0.468085 (-4025 2025);
PAINT GREEN (-4025 2025);
DISPLAY INVISIBLE (-4025 2025);
FORCEPROP 2 LAST CDS_LIB w_hdl
J 0
(-4025 2025);
PAINT MONO (-4025 2025);
DISPLAY INVISIBLE (-4025 2025);
FORCEPROP 1 LAST PART_NUMBER 064.6653F.M001
J 0
(-4025 2025);
DISPLAY 0.617021 (-4025 2025);
PAINT GREEN (-4025 2025);
DISPLAY INVISIBLE (-4025 2025);
FORCEPROP 1 LAST PACK_TYPE SMD-RG3
J 0
(-4025 2025);
DISPLAY 0.617021 (-4025 2025);
PAINT GREEN (-4025 2025);
DISPLAY INVISIBLE (-4025 2025);
FORCEPROP 0 LAST ATTRIBUTE 665K OHM
J 0
(-4000 2050);
DISPLAY 0.638298 (-4000 2050);
PAINT GREEN (-4000 2050);
DISPLAY INVISIBLE (-4000 2050);
FORCEPROP 1 LAST VALUE 665KR5B-1-GP
J 0
(-4000 2100);
DISPLAY 0.617021 (-4000 2100);
PAINT GREEN (-4000 2100);
DISPLAY INVISIBLE (-4000 2100);
FORCEPROP 1 LAST PATH I121
J 0
(-4025 2025);
DISPLAY 0.617021 (-4025 2025);
PAINT GREEN (-4025 2025);
DISPLAY INVISIBLE (-4025 2025);
FORCEADD 665KR5B-1-GP..1
(-1925 2025);
FORCEPROP 0 LAST CONFIG 064.1003F.M001
J 0
(-1900 2100);
DISPLAY 0.638298 (-1900 2100);
PAINT BROWN (-1900 2100);
DISPLAY BOTH (-1900 2100);
FORCEPROP 0 LAST NEW_VALUE 100K OHM
J 0
(-1900 2050);
DISPLAY 0.638298 (-1900 2050);
PAINT BROWN (-1900 2050);
DISPLAY BOTH (-1900 2050);
FORCEPROP 1 LAST LOCATION R12W16
J 0
(-1900 2155);
DISPLAY 0.617021 (-1900 2155);
PAINT GREEN (-1900 2155);
FORCEPROP 2 LAST TOLERANCE 0.1%
J 0
(-1900 2000);
DISPLAY 0.638298 (-1900 2000);
PAINT GREEN (-1900 2000);
FORCEPROP 2 LAST PACK_SIZE AT0805
J 0
(-1900 1900);
DISPLAY 0.638298 (-1900 1900);
PAINT GREEN (-1900 1900);
FORCEPROP 2 LAST RATED 1/8W
J 0
(-1900 1950);
DISPLAY 0.638298 (-1900 1950);
PAINT GREEN (-1900 1950);
FORCEPROP 1 LAST PATH I122
J 0
(-1925 2025);
DISPLAY 0.617021 (-1925 2025);
PAINT GREEN (-1925 2025);
DISPLAY INVISIBLE (-1925 2025);
FORCEPROP 1 LAST CDS_LMAN_SYM_OUTLINE -50,75,50,-75
J 0
(-1925 2025);
DISPLAY 0.468085 (-1925 2025);
PAINT GREEN (-1925 2025);
DISPLAY INVISIBLE (-1925 2025);
FORCEPROP 2 LAST CDS_LIB w_hdl
J 0
(-1925 2025);
PAINT MONO (-1925 2025);
DISPLAY INVISIBLE (-1925 2025);
FORCEPROP 1 LAST PART_NUMBER 064.6653F.M001
J 0
(-1925 2025);
DISPLAY 0.617021 (-1925 2025);
PAINT GREEN (-1925 2025);
DISPLAY INVISIBLE (-1925 2025);
FORCEPROP 1 LAST PACK_TYPE SMD-RG3
J 0
(-1925 2025);
DISPLAY 0.617021 (-1925 2025);
PAINT GREEN (-1925 2025);
DISPLAY INVISIBLE (-1925 2025);
FORCEPROP 0 LAST ATTRIBUTE 665K OHM
J 0
(-1900 2050);
DISPLAY 0.638298 (-1900 2050);
PAINT GREEN (-1900 2050);
DISPLAY INVISIBLE (-1900 2050);
FORCEPROP 1 LAST VALUE 665KR5B-1-GP
J 0
(-1900 2100);
DISPLAY 0.617021 (-1900 2100);
PAINT GREEN (-1900 2100);
DISPLAY INVISIBLE (-1900 2100);
FORCEADD 665KR5B-1-GP..1
(-1475 2025);
FORCEPROP 0 LAST CONFIG 064.1003F.M001
J 0
(-1450 2100);
DISPLAY 0.638298 (-1450 2100);
PAINT BROWN (-1450 2100);
DISPLAY BOTH (-1450 2100);
FORCEPROP 0 LAST NEW_VALUE 100K OHM
J 0
(-1450 2050);
DISPLAY 0.638298 (-1450 2050);
PAINT BROWN (-1450 2050);
DISPLAY BOTH (-1450 2050);
FORCEPROP 1 LAST LOCATION R12W17
J 0
(-1450 2155);
DISPLAY 0.617021 (-1450 2155);
PAINT GREEN (-1450 2155);
FORCEPROP 2 LAST TOLERANCE 0.1%
J 0
(-1450 2000);
DISPLAY 0.638298 (-1450 2000);
PAINT GREEN (-1450 2000);
FORCEPROP 2 LAST RATED 1/8W
J 0
(-1450 1950);
DISPLAY 0.638298 (-1450 1950);
PAINT GREEN (-1450 1950);
FORCEPROP 2 LAST PACK_SIZE AT0805
J 0
(-1450 1900);
DISPLAY 0.638298 (-1450 1900);
PAINT GREEN (-1450 1900);
FORCEPROP 1 LAST VALUE 665KR5B-1-GP
J 0
(-1450 2100);
DISPLAY 0.617021 (-1450 2100);
PAINT GREEN (-1450 2100);
DISPLAY INVISIBLE (-1450 2100);
FORCEPROP 0 LAST ATTRIBUTE 665K OHM
J 0
(-1450 2050);
DISPLAY 0.638298 (-1450 2050);
PAINT GREEN (-1450 2050);
DISPLAY INVISIBLE (-1450 2050);
FORCEPROP 1 LAST PACK_TYPE SMD-RG3
J 0
(-1475 2025);
DISPLAY 0.617021 (-1475 2025);
PAINT GREEN (-1475 2025);
DISPLAY INVISIBLE (-1475 2025);
FORCEPROP 1 LAST PART_NUMBER 064.6653F.M001
J 0
(-1475 2025);
DISPLAY 0.617021 (-1475 2025);
PAINT GREEN (-1475 2025);
DISPLAY INVISIBLE (-1475 2025);
FORCEPROP 2 LAST CDS_LIB w_hdl
J 0
(-1475 2025);
PAINT MONO (-1475 2025);
DISPLAY INVISIBLE (-1475 2025);
FORCEPROP 1 LAST CDS_LMAN_SYM_OUTLINE -50,75,50,-75
J 0
(-1475 2025);
DISPLAY 0.468085 (-1475 2025);
PAINT GREEN (-1475 2025);
DISPLAY INVISIBLE (-1475 2025);
FORCEPROP 1 LAST PATH I123
J 0
(-1475 2025);
DISPLAY 0.617021 (-1475 2025);
PAINT GREEN (-1475 2025);
DISPLAY INVISIBLE (-1475 2025);
FORCEADD RES..1
(-4275 4800);
FORCEPROP 1 LAST WATTAGE 1W
J 2
(-4200 4725);
DISPLAY 0.617021 (-4200 4725);
PAINT SKYBLUE (-4200 4725);
FORCEPROP 1 LAST TOLERANCE 1%
J 0
(-4350 4725);
DISPLAY 0.617021 (-4350 4725);
PAINT SKYBLUE (-4350 4725);
FORCEPROP 1 LAST PACK_TYPE 1206
J 0
(-4075 4725);
DISPLAY 0.617021 (-4075 4725);
PAINT SKYBLUE (-4075 4725);
FORCEPROP 1 LAST PART_NUMBER G52199-004
J 0
(-4325 4900);
DISPLAY 0.617021 (-4325 4900);
PAINT BLUE (-4325 4900);
FORCEPROP 1 LASTPIN (-4175 4800) $PN 2
J 0
(-4213 4812);
DISPLAY 0.617021 (-4213 4812);
PAINT ORANGE (-4213 4812);
FORCEPROP 1 LAST LOCATION R4F2
J 0
(-4325 4850);
DISPLAY 0.617021 (-4325 4850);
PAINT AQUA (-4325 4850);
FORCEPROP 1 LASTPIN (-4375 4800) $PN 1
J 0
(-4363 4812);
DISPLAY 0.617021 (-4363 4812);
PAINT ORANGE (-4363 4812);
FORCEPROP 0 LAST CONFIG 064.R0045.0711
J 0
(-4350 5000);
DISPLAY 0.638298 (-4350 5000);
PAINT BROWN (-4350 5000);
DISPLAY BOTH (-4350 5000);
FORCEPROP 0 LAST NEW_VALUE 0.004 OHM
J 0
(-4350 4950);
DISPLAY 0.638298 (-4350 4950);
PAINT BROWN (-4350 4950);
DISPLAY BOTH (-4350 4950);
FORCEPROP 1 LAST MATERIAL CHIP
J 0
(-4175 4725);
DISPLAY 0.617021 (-4175 4725);
PAINT SKYBLUE (-4175 4725);
FORCEPROP 1 LAST VALUE 0.002
J 2
(-4275 4725);
DISPLAY 0.617021 (-4275 4725);
PAINT SKYBLUE (-4275 4725);
DISPLAY INVISIBLE (-4275 4725);
FORCEPROP 2 LAST ROOM PVDDQ_ABC_PWR_VR
J 0
(-4325 4900);
DISPLAY 1.361702 (-4325 4900);
PAINT ORANGE (-4325 4900);
DISPLAY INVISIBLE (-4325 4900);
FORCEPROP 2 LAST CDS_LOCATION R4F2
J 0
(-4325 4850);
DISPLAY 0.617021 (-4325 4850);
PAINT AQUA (-4325 4850);
DISPLAY INVISIBLE (-4325 4850);
FORCEPROP 2 LAST SEC 1
J 0
(-4325 5000);
DISPLAY 0.680851 (-4325 5000);
PAINT MONO (-4325 5000);
DISPLAY INVISIBLE (-4325 5000);
FORCEPROP 2 LAST CDS_LIB mstr_discrete
J 0
(-4275 4800);
PAINT ORANGE (-4275 4800);
DISPLAY INVISIBLE (-4275 4800);
FORCEPROP 2 LAST BOM_COST PVDDQ_ABC_VR
J 0
(-4325 5000);
DISPLAY 1.361702 (-4325 5000);
PAINT ORANGE (-4325 5000);
DISPLAY INVISIBLE (-4325 5000);
FORCEPROP 2 LAST SEC_TYPE 1206
J 0
(-4325 5000);
DISPLAY 1.021277 (-4325 5000);
PAINT ORANGE (-4325 5000);
DISPLAY INVISIBLE (-4325 5000);
FORCEPROP 0 LAST CDS_SEC 1
J 0
(-4325 4950);
PAINT MONO (-4325 4950);
DISPLAY INVISIBLE (-4325 4950);
FORCEPROP 1 LAST PATH I14
J 0
(-4325 4950);
DISPLAY 0.978723 (-4325 4950);
PAINT WHITE (-4325 4950);
DISPLAY INVISIBLE (-4325 4950);
FORCEADD OFFPAGE..5
R 2
(-2825 1150);
FORCEPROP 2 LAST $XR0 218 
J 0
(-2636 1150);
DISPLAY 0.638298 (-2636 1150);
PAINT MONO (-2636 1150);
FORCEPROP 1 LAST COMMENT_BODY TRUE
J 2
(-2925 1075);
DISPLAY 1.170213 (-2925 1075);
PAINT GREEN (-2925 1075);
DISPLAY INVISIBLE (-2925 1075);
FORCEPROP 1 LAST OFFPAGE TRUE
J 2
(-3150 1025);
DISPLAY 1.170213 (-3150 1025);
PAINT GREEN (-3150 1025);
DISPLAY INVISIBLE (-3150 1025);
FORCEPROP 2 LAST CDS_LIB mstr_standard
J 0
(-2825 1150);
PAINT MONO (-2825 1150);
DISPLAY INVISIBLE (-2825 1150);
FORCEPROP 2 LAST PATH I15
J 0
(-2625 1200);
DISPLAY 1.021277 (-2625 1200);
PAINT ORANGE (-2625 1200);
DISPLAY INVISIBLE (-2625 1200);
FORCEADD OFFPAGE..5
R 2
(-2825 1200);
FORCEPROP 2 LAST $XR0 218 
J 0
(-2636 1200);
DISPLAY 0.638298 (-2636 1200);
PAINT MONO (-2636 1200);
FORCEPROP 1 LAST COMMENT_BODY TRUE
J 2
(-2925 1125);
DISPLAY 1.170213 (-2925 1125);
PAINT GREEN (-2925 1125);
DISPLAY INVISIBLE (-2925 1125);
FORCEPROP 1 LAST OFFPAGE TRUE
J 2
(-3150 1075);
DISPLAY 1.170213 (-3150 1075);
PAINT GREEN (-3150 1075);
DISPLAY INVISIBLE (-3150 1075);
FORCEPROP 2 LAST CDS_LIB mstr_standard
J 0
(-2825 1200);
PAINT MONO (-2825 1200);
DISPLAY INVISIBLE (-2825 1200);
FORCEPROP 2 LAST PATH I16
J 0
(-2625 1250);
DISPLAY 1.021277 (-2625 1250);
PAINT ORANGE (-2625 1250);
DISPLAY INVISIBLE (-2625 1250);
FORCEADD OFFPAGE..4
(-2825 1500);
FORCEPROP 2 LAST $XR0 218 
J 0
(-2639 1500);
DISPLAY 0.638298 (-2639 1500);
PAINT MONO (-2639 1500);
FORCEPROP 1 LAST COMMENT_BODY TRUE
J 0
(-2850 1400);
DISPLAY 0.680851 (-2850 1400);
PAINT PEACH (-2850 1400);
DISPLAY INVISIBLE (-2850 1400);
FORCEPROP 1 LAST OFFPAGE TRUE
J 0
(-2500 1375);
DISPLAY 0.680851 (-2500 1375);
PAINT GREEN (-2500 1375);
DISPLAY INVISIBLE (-2500 1375);
FORCEPROP 2 LAST CDS_LIB mstr_standard
J 0
(-2825 1500);
PAINT MONO (-2825 1500);
DISPLAY INVISIBLE (-2825 1500);
FORCEPROP 2 LAST PATH I17
J 0
(-2625 1550);
DISPLAY 1.021277 (-2625 1550);
PAINT ORANGE (-2625 1550);
DISPLAY INVISIBLE (-2625 1550);
FORCEADD CAP..1
R 1
(-1725 1450);
FORCEPROP 1 LAST LOCATION C12W4
J 0
(-1875 1375);
DISPLAY 0.617021 (-1875 1375);
PAINT AQUA (-1875 1375);
FORCEPROP 1 LASTPIN (-1625 1450) $PN 2
J 0
(-1605 1460);
DISPLAY 0.617021 (-1605 1460);
PAINT MONO (-1605 1460);
FORCEPROP 1 LASTPIN (-1825 1450) $PN 1
J 0
(-1855 1460);
DISPLAY 0.617021 (-1855 1460);
PAINT MONO (-1855 1460);
FORCEPROP 1 LAST TOLERANCE 5%
J 0
(-1875 1225);
DISPLAY 0.617021 (-1875 1225);
PAINT SKYBLUE (-1875 1225);
FORCEPROP 1 LAST VOLTAGE 50V
J 0
(-1875 1275);
DISPLAY 0.617021 (-1875 1275);
PAINT SKYBLUE (-1875 1275);
FORCEPROP 1 LAST VALUE 47.0PF
J 0
(-1875 1325);
DISPLAY 0.617021 (-1875 1325);
PAINT SKYBLUE (-1875 1325);
FORCEPROP 1 LAST PACK_TYPE 0402LF
J 0
(-1700 1275);
DISPLAY 0.617021 (-1700 1275);
PAINT SKYBLUE (-1700 1275);
FORCEPROP 1 LAST PART_NUMBER A36095-025
J 0
(-1700 1325);
DISPLAY 0.617021 (-1700 1325);
PAINT BLUE (-1700 1325);
FORCEPROP 1 LAST MATERIAL COG
J 0
(-1700 1375);
DISPLAY 0.617021 (-1700 1375);
PAINT SKYBLUE (-1700 1375);
FORCEPROP 2 LAST BOM_COST SM_HM
R 1
J 0
(-1925 1500);
DISPLAY 1.021277 (-1925 1500);
PAINT ORANGE (-1925 1500);
DISPLAY INVISIBLE (-1925 1500);
FORCEPROP 2 LAST CDS_LIB mstr_discrete
R 1
J 0
(-1725 1450);
DISPLAY 1.361702 (-1725 1450);
PAINT ORANGE (-1725 1450);
DISPLAY INVISIBLE (-1725 1450);
FORCEPROP 2 LAST SEC_TYPE 0402LF
R 1
J 0
(-1925 1500);
PAINT MONO (-1925 1500);
DISPLAY INVISIBLE (-1925 1500);
FORCEPROP 2 LAST SEC 1
R 1
J 0
(-1925 1500);
DISPLAY 0.936170 (-1925 1500);
PAINT MONO (-1925 1500);
DISPLAY INVISIBLE (-1925 1500);
FORCEPROP 2 LAST ROOM BMC_VOLT_MONITOR
R 1
J 0
(-1875 1500);
DISPLAY 1.021277 (-1875 1500);
PAINT ORANGE (-1875 1500);
DISPLAY INVISIBLE (-1875 1500);
FORCEPROP 2 LAST CDS_LOCATION C12W4
R 1
J 0
(-1825 1500);
DISPLAY 0.617021 (-1825 1500);
PAINT AQUA (-1825 1500);
DISPLAY INVISIBLE (-1825 1500);
FORCEPROP 0 LAST CDS_SEC 1
R 1
J 0
(-1850 1400);
PAINT MONO (-1850 1400);
DISPLAY INVISIBLE (-1850 1400);
FORCEPROP 1 LAST PATH I18
R 1
J 0
(-1875 1500);
DISPLAY 0.978723 (-1875 1500);
PAINT WHITE (-1875 1500);
DISPLAY INVISIBLE (-1875 1500);
FORCEADD BSL308C-H6327-GP..1
(-3250 2000);
FORCEPROP 2 LASTPIN (-3525 2000) $PN 2
J 2
(-3535 2010);
DISPLAY 0.808511 (-3535 2010);
PAINT ORANGE (-3535 2010);
FORCEPROP 2 LASTPIN (-2975 2000) $PN 5
J 0
(-2965 2010);
DISPLAY 0.808511 (-2965 2010);
PAINT ORANGE (-2965 2010);
FORCEPROP 2 LASTPIN (-2975 2200) $PN 6
J 0
(-2965 2210);
DISPLAY 0.808511 (-2965 2210);
PAINT ORANGE (-2965 2210);
FORCEPROP 2 LASTPIN (-3525 2200) $PN 1
J 2
(-3535 2210);
DISPLAY 0.808511 (-3535 2210);
PAINT ORANGE (-3535 2210);
FORCEPROP 2 LASTPIN (-3525 1800) $PN 3
J 2
(-3535 1810);
DISPLAY 0.808511 (-3535 1810);
PAINT ORANGE (-3535 1810);
FORCEPROP 2 LASTPIN (-2975 1800) $PN 4
J 0
(-2965 1810);
DISPLAY 0.808511 (-2965 1810);
PAINT ORANGE (-2965 1810);
FORCEPROP 1 LAST VALUE BSL308C-H6327-GP
J 0
(-3375 1700);
DISPLAY 0.617021 (-3375 1700);
PAINT GREEN (-3375 1700);
FORCEPROP 1 LAST LOCATION Q12W2
J 0
(-3375 2275);
DISPLAY 0.617021 (-3375 2275);
PAINT GREEN (-3375 2275);
FORCEPROP 1 LAST PACK_TYPE DISCRET-GB1
J 0
(-3250 2000);
DISPLAY 0.617021 (-3250 2000);
PAINT GREEN (-3250 2000);
DISPLAY INVISIBLE (-3250 2000);
FORCEPROP 2 LAST SEC 1
J 0
(-3375 2325);
DISPLAY 0.680851 (-3375 2325);
PAINT MONO (-3375 2325);
DISPLAY INVISIBLE (-3375 2325);
FORCEPROP 2 LAST SEC_TYPE DISCRET-GB1
J 0
(-3375 2325);
DISPLAY 1.021277 (-3375 2325);
PAINT ORANGE (-3375 2325);
DISPLAY INVISIBLE (-3375 2325);
FORCEPROP 1 LAST CDS_LMAN_SYM_OUTLINE -125,250,125,-250
J 0
(-3250 2000);
DISPLAY 0.468085 (-3250 2000);
PAINT GREEN (-3250 2000);
DISPLAY INVISIBLE (-3250 2000);
FORCEPROP 2 LAST CDS_LIB w_hdl
J 0
(-3250 2000);
PAINT MONO (-3250 2000);
DISPLAY INVISIBLE (-3250 2000);
FORCEPROP 1 LAST PART_NUMBER 075.00308.007C
J 0
(-3250 2000);
DISPLAY 0.617021 (-3250 2000);
PAINT GREEN (-3250 2000);
DISPLAY INVISIBLE (-3250 2000);
FORCEPROP 0 LAST CDS_LOCATION Q12W2
J 0
(-3375 2325);
PAINT MONO (-3375 2325);
DISPLAY INVISIBLE (-3375 2325);
FORCEPROP 0 LAST CDS_SEC 1
J 0
(-3375 2325);
PAINT MONO (-3375 2325);
DISPLAY INVISIBLE (-3375 2325);
FORCEPROP 1 LAST PATH I19
J 0
(-3250 2000);
DISPLAY 0.617021 (-3250 2000);
PAINT GREEN (-3250 2000);
DISPLAY INVISIBLE (-3250 2000);
FORCEADD P12V_STBY..1
(-4525 2850);
FORCEPROP 3 LASTPIN (-4525 2800) SIG_NAME P12V_STBY\g
J 0
(-4515 2810);
DISPLAY 0.659574 (-4515 2810);
PAINT MONO (-4515 2810);
DISPLAY INVISIBLE (-4515 2810);
FORCEPROP 1 LAST HDL_POWER P12V_STBY
J 0
(-4825 2725);
DISPLAY 0.872340 (-4825 2725);
PAINT ORANGE (-4825 2725);
DISPLAY INVISIBLE (-4825 2725);
FORCEPROP 1 LAST BODY_TYPE PLUMBING
J 0
(-4570 2807);
DISPLAY 0.340426 (-4570 2807);
PAINT GREEN (-4570 2807);
DISPLAY INVISIBLE (-4570 2807);
FORCEPROP 1 LAST VOLTAGE 12.0V
J 0
(-4570 2807);
DISPLAY 0.340426 (-4570 2807);
PAINT SKYBLUE (-4570 2807);
DISPLAY INVISIBLE (-4570 2807);
FORCEPROP 1 LAST SIZE 1B
J 0
(-4480 2872);
DISPLAY 0.340426 (-4480 2872);
PAINT GREEN (-4480 2872);
DISPLAY INVISIBLE (-4480 2872);
FORCEPROP 2 LAST CDS_LIB mstr_symbols
J 0
(-4525 2850);
PAINT ORANGE (-4525 2850);
DISPLAY INVISIBLE (-4525 2850);
FORCEPROP 1 LAST PATH I2
J 0
(-4480 2852);
DISPLAY 0.340426 (-4480 2852);
PAINT GREEN (-4480 2852);
DISPLAY INVISIBLE (-4480 2852);
FORCEADD GND..1
(-2925 1900);
FORCEPROP 3 LASTPIN (-2925 1950) SIG_NAME GND\g
J 0
(-2915 1960);
DISPLAY 0.659574 (-2915 1960);
PAINT MONO (-2915 1960);
DISPLAY INVISIBLE (-2915 1960);
FORCEPROP 1 LAST HDL_POWER GND
J 0
(-2925 2050);
DISPLAY 1.170213 (-2925 2050);
PAINT GREEN (-2925 2050);
DISPLAY INVISIBLE (-2925 2050);
FORCEPROP 1 LAST BODY_TYPE PLUMBING
J 0
(-2970 1857);
DISPLAY 0.340426 (-2970 1857);
PAINT GREEN (-2970 1857);
DISPLAY INVISIBLE (-2970 1857);
FORCEPROP 2 LAST CDS_LIB mstr_symbols
J 0
(-2925 1900);
PAINT ORANGE (-2925 1900);
DISPLAY INVISIBLE (-2925 1900);
FORCEPROP 1 LAST SIZE 1B
J 0
(-2850 1850);
DISPLAY 1.170213 (-2850 1850);
PAINT AQUA (-2850 1850);
DISPLAY INVISIBLE (-2850 1850);
FORCEPROP 1 LAST VOLTAGE 0.0V
J 0
(-2970 1857);
DISPLAY 0.340426 (-2970 1857);
PAINT SKYBLUE (-2970 1857);
DISPLAY INVISIBLE (-2970 1857);
FORCEPROP 1 LAST PATH I20
J 0
(-2850 1900);
DISPLAY 0.872340 (-2850 1900);
PAINT AQUA (-2850 1900);
DISPLAY INVISIBLE (-2850 1900);
FORCEADD RES..2
(-2725 2400);
FORCEPROP 1 LAST VALUE 100.0K
J 0
(-2680 2475);
DISPLAY 0.617021 (-2680 2475);
PAINT SKYBLUE (-2680 2475);
FORCEPROP 1 LAST TOLERANCE 1%
J 0
(-2680 2425);
DISPLAY 0.617021 (-2680 2425);
PAINT SKYBLUE (-2680 2425);
FORCEPROP 1 LAST LOCATION R12W9
J 0
(-2675 2525);
DISPLAY 0.617021 (-2675 2525);
PAINT AQUA (-2675 2525);
FORCEPROP 1 LAST WATTAGE 1/10W
J 0
(-2685 2375);
DISPLAY 0.617021 (-2685 2375);
PAINT SKYBLUE (-2685 2375);
FORCEPROP 1 LASTPIN (-2725 2300) $PN 2
J 0
(-2720 2310);
DISPLAY 0.617021 (-2720 2310);
PAINT ORANGE (-2720 2310);
FORCEPROP 1 LAST MATERIAL CHIP
J 0
(-2685 2325);
DISPLAY 0.617021 (-2685 2325);
PAINT SKYBLUE (-2685 2325);
FORCEPROP 1 LASTPIN (-2725 2500) $PN 1
J 0
(-2720 2462);
DISPLAY 0.617021 (-2720 2462);
PAINT ORANGE (-2720 2462);
FORCEPROP 1 LAST PACK_TYPE 0603
J 0
(-2685 2225);
DISPLAY 0.617021 (-2685 2225);
PAINT SKYBLUE (-2685 2225);
FORCEPROP 1 LAST PART_NUMBER G22026-050
J 0
(-2685 2275);
DISPLAY 0.617021 (-2685 2275);
PAINT BLUE (-2685 2275);
FORCEPROP 2 LAST SEC_TYPE 0603
J 0
(-2675 2625);
DISPLAY 1.021277 (-2675 2625);
PAINT ORANGE (-2675 2625);
DISPLAY INVISIBLE (-2675 2625);
FORCEPROP 2 LAST SEC 1
J 0
(-2675 2625);
DISPLAY 0.680851 (-2675 2625);
PAINT MONO (-2675 2625);
DISPLAY INVISIBLE (-2675 2625);
FORCEPROP 2 LAST BOM_COST PROC_SOCKET
J 0
(-2650 2550);
DISPLAY 1.021277 (-2650 2550);
PAINT ORANGE (-2650 2550);
DISPLAY INVISIBLE (-2650 2550);
FORCEPROP 2 LAST ROOM CPU0
J 0
(-2650 2500);
DISPLAY 1.021277 (-2650 2500);
PAINT ORANGE (-2650 2500);
DISPLAY INVISIBLE (-2650 2500);
FORCEPROP 2 LAST CDS_LIB mstr_discrete
J 0
(-2725 2400);
PAINT ORANGE (-2725 2400);
DISPLAY INVISIBLE (-2725 2400);
FORCEPROP 2 LAST CDS_LOCATION R12W9
J 0
(-2675 2525);
DISPLAY 0.617021 (-2675 2525);
PAINT AQUA (-2675 2525);
DISPLAY INVISIBLE (-2675 2525);
FORCEPROP 0 LAST CDS_SEC 1
J 0
(-2675 2575);
PAINT MONO (-2675 2575);
DISPLAY INVISIBLE (-2675 2575);
FORCEPROP 1 LAST PATH I21
J 0
(-2675 2575);
DISPLAY 0.978723 (-2675 2575);
PAINT WHITE (-2675 2575);
DISPLAY INVISIBLE (-2675 2575);
FORCEADD OFFPAGE..5
R 2
(-2825 3250);
FORCEPROP 2 LAST $XR0 215 
J 0
(-2636 3250);
DISPLAY 0.638298 (-2636 3250);
PAINT MONO (-2636 3250);
FORCEPROP 1 LAST COMMENT_BODY TRUE
J 2
(-2925 3175);
DISPLAY 1.170213 (-2925 3175);
PAINT GREEN (-2925 3175);
DISPLAY INVISIBLE (-2925 3175);
FORCEPROP 1 LAST OFFPAGE TRUE
J 2
(-3150 3125);
DISPLAY 1.170213 (-3150 3125);
PAINT GREEN (-3150 3125);
DISPLAY INVISIBLE (-3150 3125);
FORCEPROP 2 LAST CDS_LIB mstr_standard
J 0
(-2825 3250);
PAINT MONO (-2825 3250);
DISPLAY INVISIBLE (-2825 3250);
FORCEPROP 2 LAST PATH I22
J 0
(-2625 3300);
DISPLAY 1.021277 (-2625 3300);
PAINT ORANGE (-2625 3300);
DISPLAY INVISIBLE (-2625 3300);
FORCEADD P12V_NVDIMM_DEF..1
(-2675 2850);
FORCEPROP 3 LASTPIN (-2675 2800) SIG_NAME P12V_NVDIMM_DEF\g
J 0
(-2665 2810);
DISPLAY 0.659574 (-2665 2810);
PAINT MONO (-2665 2810);
DISPLAY INVISIBLE (-2665 2810);
FORCEPROP 1 LAST HDL_POWER P12V_NVDIMM_DEF
J 1
(-2675 2900);
DISPLAY 0.872340 (-2675 2900);
PAINT GREEN (-2675 2900);
DISPLAY INVISIBLE (-2675 2900);
FORCEPROP 1 LAST BODY_TYPE PLUMBING
J 0
(-2720 2807);
DISPLAY 0.340426 (-2720 2807);
PAINT GREEN (-2720 2807);
DISPLAY INVISIBLE (-2720 2807);
FORCEPROP 1 LAST VOLTAGE 12.0
J 0
(-2720 2807);
DISPLAY 0.340426 (-2720 2807);
PAINT SKYBLUE (-2720 2807);
DISPLAY INVISIBLE (-2720 2807);
FORCEPROP 2 LAST CDS_LIB mstr_symbols
J 0
(-2675 2850);
PAINT ORANGE (-2675 2850);
DISPLAY INVISIBLE (-2675 2850);
FORCEPROP 1 LAST PATH I23
J 0
(-2625 2875);
DISPLAY 0.872340 (-2625 2875);
PAINT AQUA (-2625 2875);
DISPLAY INVISIBLE (-2625 2875);
FORCEADD OFFPAGE..4
(-2825 3600);
FORCEPROP 2 LAST $XR0 215 
J 0
(-2639 3600);
DISPLAY 0.638298 (-2639 3600);
PAINT MONO (-2639 3600);
FORCEPROP 1 LAST COMMENT_BODY TRUE
J 0
(-2850 3500);
DISPLAY 0.680851 (-2850 3500);
PAINT PEACH (-2850 3500);
DISPLAY INVISIBLE (-2850 3500);
FORCEPROP 1 LAST OFFPAGE TRUE
J 0
(-2500 3475);
DISPLAY 0.680851 (-2500 3475);
PAINT GREEN (-2500 3475);
DISPLAY INVISIBLE (-2500 3475);
FORCEPROP 2 LAST CDS_LIB mstr_standard
J 0
(-2825 3600);
PAINT MONO (-2825 3600);
DISPLAY INVISIBLE (-2825 3600);
FORCEPROP 2 LAST PATH I24
J 0
(-2625 3650);
DISPLAY 1.021277 (-2625 3650);
PAINT ORANGE (-2625 3650);
DISPLAY INVISIBLE (-2625 3650);
FORCEADD OFFPAGE..5
R 2
(-2825 3300);
FORCEPROP 2 LAST $XR0 215 
J 0
(-2636 3300);
DISPLAY 0.638298 (-2636 3300);
PAINT MONO (-2636 3300);
FORCEPROP 1 LAST COMMENT_BODY TRUE
J 2
(-2925 3225);
DISPLAY 1.170213 (-2925 3225);
PAINT GREEN (-2925 3225);
DISPLAY INVISIBLE (-2925 3225);
FORCEPROP 1 LAST OFFPAGE TRUE
J 2
(-3150 3175);
DISPLAY 1.170213 (-3150 3175);
PAINT GREEN (-3150 3175);
DISPLAY INVISIBLE (-3150 3175);
FORCEPROP 2 LAST CDS_LIB mstr_standard
J 0
(-2825 3300);
PAINT MONO (-2825 3300);
DISPLAY INVISIBLE (-2825 3300);
FORCEPROP 2 LAST PATH I25
J 0
(-2625 3350);
DISPLAY 1.021277 (-2625 3350);
PAINT ORANGE (-2625 3350);
DISPLAY INVISIBLE (-2625 3350);
FORCEADD RES..1
(-1725 2700);
FORCEPROP 1 LAST TOLERANCE 1%
J 0
(-1800 2625);
DISPLAY 0.617021 (-1800 2625);
PAINT SKYBLUE (-1800 2625);
FORCEPROP 1 LAST WATTAGE 1W
J 2
(-1650 2625);
DISPLAY 0.617021 (-1650 2625);
PAINT SKYBLUE (-1650 2625);
FORCEPROP 1 LAST MATERIAL CHIP
J 0
(-1625 2625);
DISPLAY 0.617021 (-1625 2625);
PAINT SKYBLUE (-1625 2625);
FORCEPROP 1 LAST PACK_TYPE 1206
J 0
(-1525 2625);
DISPLAY 0.617021 (-1525 2625);
PAINT SKYBLUE (-1525 2625);
FORCEPROP 1 LAST LOCATION R9M4
J 0
(-1775 2750);
DISPLAY 0.617021 (-1775 2750);
PAINT AQUA (-1775 2750);
FORCEPROP 1 LAST PART_NUMBER G52199-004
J 0
(-1775 2800);
DISPLAY 0.617021 (-1775 2800);
PAINT BLUE (-1775 2800);
FORCEPROP 1 LASTPIN (-1825 2700) $PN 1
J 0
(-1813 2712);
DISPLAY 0.617021 (-1813 2712);
PAINT ORANGE (-1813 2712);
FORCEPROP 1 LASTPIN (-1625 2700) $PN 2
J 0
(-1663 2712);
DISPLAY 0.617021 (-1663 2712);
PAINT ORANGE (-1663 2712);
FORCEPROP 0 LAST NEW_VALUE 0.004 OHM
J 0
(-1800 2850);
DISPLAY 0.638298 (-1800 2850);
PAINT BROWN (-1800 2850);
DISPLAY BOTH (-1800 2850);
FORCEPROP 0 LAST CONFIG 064.R0045.0711
J 0
(-1800 2900);
DISPLAY 0.638298 (-1800 2900);
PAINT BROWN (-1800 2900);
DISPLAY BOTH (-1800 2900);
FORCEPROP 1 LAST VALUE 0.002
J 2
(-1750 2625);
DISPLAY 0.617021 (-1750 2625);
PAINT SKYBLUE (-1750 2625);
DISPLAY INVISIBLE (-1750 2625);
FORCEPROP 2 LAST ROOM PVDDQ_ABC_PWR_VR
J 0
(-1775 2800);
DISPLAY 1.361702 (-1775 2800);
PAINT ORANGE (-1775 2800);
DISPLAY INVISIBLE (-1775 2800);
FORCEPROP 2 LAST SEC 1
J 0
(-1775 2900);
DISPLAY 0.680851 (-1775 2900);
PAINT MONO (-1775 2900);
DISPLAY INVISIBLE (-1775 2900);
FORCEPROP 2 LAST CDS_LIB mstr_discrete
J 0
(-1725 2700);
PAINT ORANGE (-1725 2700);
DISPLAY INVISIBLE (-1725 2700);
FORCEPROP 2 LAST BOM_COST PVDDQ_ABC_VR
J 0
(-1775 2900);
DISPLAY 1.361702 (-1775 2900);
PAINT ORANGE (-1775 2900);
DISPLAY INVISIBLE (-1775 2900);
FORCEPROP 2 LAST SEC_TYPE 1206
J 0
(-1775 2900);
DISPLAY 1.021277 (-1775 2900);
PAINT ORANGE (-1775 2900);
DISPLAY INVISIBLE (-1775 2900);
FORCEPROP 2 LAST CDS_LOCATION R9M4
J 0
(-1775 2750);
DISPLAY 0.617021 (-1775 2750);
PAINT AQUA (-1775 2750);
DISPLAY INVISIBLE (-1775 2750);
FORCEPROP 0 LAST CDS_SEC 1
J 0
(-1775 2850);
PAINT MONO (-1775 2850);
DISPLAY INVISIBLE (-1775 2850);
FORCEPROP 1 LAST PATH I29
J 0
(-1775 2850);
DISPLAY 0.978723 (-1775 2850);
PAINT WHITE (-1775 2850);
DISPLAY INVISIBLE (-1775 2850);
FORCEADD P12V_STBY..1
(-1975 2850);
FORCEPROP 3 LASTPIN (-1975 2800) SIG_NAME P12V_STBY\g
J 0
(-1965 2810);
DISPLAY 0.659574 (-1965 2810);
PAINT MONO (-1965 2810);
DISPLAY INVISIBLE (-1965 2810);
FORCEPROP 1 LAST HDL_POWER P12V_STBY
J 0
(-2275 2725);
DISPLAY 0.872340 (-2275 2725);
PAINT ORANGE (-2275 2725);
DISPLAY INVISIBLE (-2275 2725);
FORCEPROP 1 LAST BODY_TYPE PLUMBING
J 0
(-2020 2807);
DISPLAY 0.340426 (-2020 2807);
PAINT GREEN (-2020 2807);
DISPLAY INVISIBLE (-2020 2807);
FORCEPROP 2 LAST CDS_LIB mstr_symbols
J 0
(-1975 2850);
PAINT ORANGE (-1975 2850);
DISPLAY INVISIBLE (-1975 2850);
FORCEPROP 1 LAST SIZE 1B
J 0
(-1930 2872);
DISPLAY 0.340426 (-1930 2872);
PAINT GREEN (-1930 2872);
DISPLAY INVISIBLE (-1930 2872);
FORCEPROP 1 LAST VOLTAGE 12.0V
J 0
(-2020 2807);
DISPLAY 0.340426 (-2020 2807);
PAINT SKYBLUE (-2020 2807);
DISPLAY INVISIBLE (-2020 2807);
FORCEPROP 1 LAST PATH I30
J 0
(-1930 2852);
DISPLAY 0.340426 (-1930 2852);
PAINT GREEN (-1930 2852);
DISPLAY INVISIBLE (-1930 2852);
FORCEADD OFFPAGE..5
R 2
(-275 1150);
FORCEPROP 2 LAST $XR0 226 
J 0
(-86 1150);
DISPLAY 0.638298 (-86 1150);
PAINT MONO (-86 1150);
FORCEPROP 1 LAST COMMENT_BODY TRUE
J 2
(-375 1075);
DISPLAY 1.170213 (-375 1075);
PAINT GREEN (-375 1075);
DISPLAY INVISIBLE (-375 1075);
FORCEPROP 1 LAST OFFPAGE TRUE
J 2
(-600 1025);
DISPLAY 1.170213 (-600 1025);
PAINT GREEN (-600 1025);
DISPLAY INVISIBLE (-600 1025);
FORCEPROP 2 LAST CDS_LIB mstr_standard
J 0
(-275 1150);
PAINT MONO (-275 1150);
DISPLAY INVISIBLE (-275 1150);
FORCEPROP 2 LAST PATH I31
J 0
(-75 1200);
DISPLAY 1.021277 (-75 1200);
PAINT ORANGE (-75 1200);
DISPLAY INVISIBLE (-75 1200);
FORCEADD OFFPAGE..5
R 2
(-275 1200);
FORCEPROP 2 LAST $XR0 226 
J 0
(-86 1200);
DISPLAY 0.638298 (-86 1200);
PAINT MONO (-86 1200);
FORCEPROP 1 LAST COMMENT_BODY TRUE
J 2
(-375 1125);
DISPLAY 1.170213 (-375 1125);
PAINT GREEN (-375 1125);
DISPLAY INVISIBLE (-375 1125);
FORCEPROP 1 LAST OFFPAGE TRUE
J 2
(-600 1075);
DISPLAY 1.170213 (-600 1075);
PAINT GREEN (-600 1075);
DISPLAY INVISIBLE (-600 1075);
FORCEPROP 2 LAST CDS_LIB mstr_standard
J 0
(-275 1200);
PAINT MONO (-275 1200);
DISPLAY INVISIBLE (-275 1200);
FORCEPROP 2 LAST PATH I32
J 0
(-75 1250);
DISPLAY 1.021277 (-75 1250);
PAINT ORANGE (-75 1250);
DISPLAY INVISIBLE (-75 1250);
FORCEADD OFFPAGE..4
(-275 1500);
FORCEPROP 2 LAST $XR0 226 
J 0
(-89 1500);
DISPLAY 0.638298 (-89 1500);
PAINT MONO (-89 1500);
FORCEPROP 1 LAST COMMENT_BODY TRUE
J 0
(-300 1400);
DISPLAY 0.680851 (-300 1400);
PAINT PEACH (-300 1400);
DISPLAY INVISIBLE (-300 1400);
FORCEPROP 1 LAST OFFPAGE TRUE
J 0
(50 1375);
DISPLAY 0.680851 (50 1375);
PAINT GREEN (50 1375);
DISPLAY INVISIBLE (50 1375);
FORCEPROP 2 LAST CDS_LIB mstr_standard
J 0
(-275 1500);
PAINT MONO (-275 1500);
DISPLAY INVISIBLE (-275 1500);
FORCEPROP 2 LAST PATH I33
J 0
(-75 1550);
DISPLAY 1.021277 (-75 1550);
PAINT ORANGE (-75 1550);
DISPLAY INVISIBLE (-75 1550);
FORCEADD BSL308C-H6327-GP..1
(-700 2000);
FORCEPROP 2 LASTPIN (-975 2200) $PN 1
J 2
(-985 2210);
DISPLAY 0.808511 (-985 2210);
PAINT ORANGE (-985 2210);
FORCEPROP 1 LAST LOCATION Q12W4
J 0
(-825 2275);
DISPLAY 0.617021 (-825 2275);
PAINT GREEN (-825 2275);
FORCEPROP 2 LASTPIN (-975 1800) $PN 3
J 2
(-985 1810);
DISPLAY 0.808511 (-985 1810);
PAINT ORANGE (-985 1810);
FORCEPROP 1 LAST VALUE BSL308C-H6327-GP
J 0
(-825 1700);
DISPLAY 0.617021 (-825 1700);
PAINT GREEN (-825 1700);
FORCEPROP 2 LASTPIN (-425 1800) $PN 4
J 0
(-415 1810);
DISPLAY 0.808511 (-415 1810);
PAINT ORANGE (-415 1810);
FORCEPROP 2 LASTPIN (-425 2000) $PN 5
J 0
(-415 2010);
DISPLAY 0.808511 (-415 2010);
PAINT ORANGE (-415 2010);
FORCEPROP 2 LASTPIN (-425 2200) $PN 6
J 0
(-415 2210);
DISPLAY 0.808511 (-415 2210);
PAINT ORANGE (-415 2210);
FORCEPROP 2 LASTPIN (-975 2000) $PN 2
J 2
(-985 2010);
DISPLAY 0.808511 (-985 2010);
PAINT ORANGE (-985 2010);
FORCEPROP 1 LAST PART_NUMBER 075.00308.007C
J 0
(-700 2000);
DISPLAY 0.617021 (-700 2000);
PAINT GREEN (-700 2000);
DISPLAY INVISIBLE (-700 2000);
FORCEPROP 2 LAST CDS_LIB w_hdl
J 0
(-700 2000);
PAINT MONO (-700 2000);
DISPLAY INVISIBLE (-700 2000);
FORCEPROP 1 LAST CDS_LMAN_SYM_OUTLINE -125,250,125,-250
J 0
(-700 2000);
DISPLAY 0.468085 (-700 2000);
PAINT GREEN (-700 2000);
DISPLAY INVISIBLE (-700 2000);
FORCEPROP 2 LAST SEC_TYPE DISCRET-GB1
J 0
(-825 2325);
DISPLAY 1.021277 (-825 2325);
PAINT ORANGE (-825 2325);
DISPLAY INVISIBLE (-825 2325);
FORCEPROP 2 LAST SEC 1
J 0
(-825 2325);
DISPLAY 0.680851 (-825 2325);
PAINT MONO (-825 2325);
DISPLAY INVISIBLE (-825 2325);
FORCEPROP 1 LAST PACK_TYPE DISCRET-GB1
J 0
(-700 2000);
DISPLAY 0.617021 (-700 2000);
PAINT GREEN (-700 2000);
DISPLAY INVISIBLE (-700 2000);
FORCEPROP 0 LAST CDS_LOCATION Q12W4
J 0
(-825 2325);
PAINT MONO (-825 2325);
DISPLAY INVISIBLE (-825 2325);
FORCEPROP 0 LAST CDS_SEC 1
J 0
(-825 2325);
PAINT MONO (-825 2325);
DISPLAY INVISIBLE (-825 2325);
FORCEPROP 1 LAST PATH I35
J 0
(-700 2000);
DISPLAY 0.617021 (-700 2000);
PAINT GREEN (-700 2000);
DISPLAY INVISIBLE (-700 2000);
FORCEADD GND..1
(-375 1900);
FORCEPROP 3 LASTPIN (-375 1950) SIG_NAME GND\g
J 0
(-365 1960);
DISPLAY 0.659574 (-365 1960);
PAINT MONO (-365 1960);
DISPLAY INVISIBLE (-365 1960);
FORCEPROP 1 LAST HDL_POWER GND
J 0
(-375 2050);
DISPLAY 1.170213 (-375 2050);
PAINT GREEN (-375 2050);
DISPLAY INVISIBLE (-375 2050);
FORCEPROP 1 LAST BODY_TYPE PLUMBING
J 0
(-420 1857);
DISPLAY 0.340426 (-420 1857);
PAINT GREEN (-420 1857);
DISPLAY INVISIBLE (-420 1857);
FORCEPROP 1 LAST VOLTAGE 0.0V
J 0
(-420 1857);
DISPLAY 0.340426 (-420 1857);
PAINT SKYBLUE (-420 1857);
DISPLAY INVISIBLE (-420 1857);
FORCEPROP 1 LAST SIZE 1B
J 0
(-300 1850);
DISPLAY 1.170213 (-300 1850);
PAINT AQUA (-300 1850);
DISPLAY INVISIBLE (-300 1850);
FORCEPROP 2 LAST CDS_LIB mstr_symbols
J 0
(-375 1900);
PAINT ORANGE (-375 1900);
DISPLAY INVISIBLE (-375 1900);
FORCEPROP 1 LAST PATH I36
J 0
(-300 1900);
DISPLAY 0.872340 (-300 1900);
PAINT AQUA (-300 1900);
DISPLAY INVISIBLE (-300 1900);
FORCEADD RES..2
(-175 2400);
FORCEPROP 1 LAST TOLERANCE 1%
J 0
(-130 2425);
DISPLAY 0.617021 (-130 2425);
PAINT SKYBLUE (-130 2425);
FORCEPROP 1 LAST LOCATION R12W19
J 0
(-125 2525);
DISPLAY 0.617021 (-125 2525);
PAINT AQUA (-125 2525);
FORCEPROP 1 LASTPIN (-175 2300) $PN 2
J 0
(-170 2310);
DISPLAY 0.617021 (-170 2310);
PAINT ORANGE (-170 2310);
FORCEPROP 1 LASTPIN (-175 2500) $PN 1
J 0
(-170 2462);
DISPLAY 0.617021 (-170 2462);
PAINT ORANGE (-170 2462);
FORCEPROP 1 LAST PACK_TYPE 0603
J 0
(-135 2225);
DISPLAY 0.617021 (-135 2225);
PAINT SKYBLUE (-135 2225);
FORCEPROP 1 LAST PART_NUMBER G22026-050
J 0
(-135 2275);
DISPLAY 0.617021 (-135 2275);
PAINT BLUE (-135 2275);
FORCEPROP 1 LAST MATERIAL CHIP
J 0
(-135 2325);
DISPLAY 0.617021 (-135 2325);
PAINT SKYBLUE (-135 2325);
FORCEPROP 1 LAST WATTAGE 1/10W
J 0
(-135 2375);
DISPLAY 0.617021 (-135 2375);
PAINT SKYBLUE (-135 2375);
FORCEPROP 1 LAST VALUE 100.0K
J 0
(-130 2475);
DISPLAY 0.617021 (-130 2475);
PAINT SKYBLUE (-130 2475);
FORCEPROP 2 LAST CDS_LIB mstr_discrete
J 0
(-175 2400);
PAINT ORANGE (-175 2400);
DISPLAY INVISIBLE (-175 2400);
FORCEPROP 2 LAST ROOM CPU0
J 0
(-100 2500);
DISPLAY 1.021277 (-100 2500);
PAINT ORANGE (-100 2500);
DISPLAY INVISIBLE (-100 2500);
FORCEPROP 2 LAST BOM_COST PROC_SOCKET
J 0
(-100 2550);
DISPLAY 1.021277 (-100 2550);
PAINT ORANGE (-100 2550);
DISPLAY INVISIBLE (-100 2550);
FORCEPROP 2 LAST SEC 1
J 0
(-125 2625);
DISPLAY 0.680851 (-125 2625);
PAINT MONO (-125 2625);
DISPLAY INVISIBLE (-125 2625);
FORCEPROP 2 LAST SEC_TYPE 0603
J 0
(-125 2625);
DISPLAY 1.021277 (-125 2625);
PAINT ORANGE (-125 2625);
DISPLAY INVISIBLE (-125 2625);
FORCEPROP 2 LAST CDS_LOCATION R12W19
J 0
(-125 2525);
DISPLAY 0.617021 (-125 2525);
PAINT AQUA (-125 2525);
DISPLAY INVISIBLE (-125 2525);
FORCEPROP 0 LAST CDS_SEC 1
J 0
(-125 2575);
PAINT MONO (-125 2575);
DISPLAY INVISIBLE (-125 2575);
FORCEPROP 1 LAST PATH I37
J 0
(-125 2575);
DISPLAY 0.978723 (-125 2575);
PAINT WHITE (-125 2575);
DISPLAY INVISIBLE (-125 2575);
FORCEADD P12V_NVDIMM_KLM..1
(-125 2850);
FORCEPROP 3 LASTPIN (-125 2800) SIG_NAME P12V_NVDIMM_KLM\g
J 0
(-115 2810);
DISPLAY 0.659574 (-115 2810);
PAINT MONO (-115 2810);
DISPLAY INVISIBLE (-115 2810);
FORCEPROP 1 LAST HDL_POWER P12V_NVDIMM_KLM
J 1
(-125 2900);
DISPLAY 0.872340 (-125 2900);
PAINT GREEN (-125 2900);
DISPLAY INVISIBLE (-125 2900);
FORCEPROP 1 LAST BODY_TYPE PLUMBING
J 0
(-170 2807);
DISPLAY 0.340426 (-170 2807);
PAINT GREEN (-170 2807);
DISPLAY INVISIBLE (-170 2807);
FORCEPROP 2 LAST CDS_LIB mstr_symbols
J 0
(-125 2850);
PAINT ORANGE (-125 2850);
DISPLAY INVISIBLE (-125 2850);
FORCEPROP 1 LAST VOLTAGE 12.0
J 0
(-170 2807);
DISPLAY 0.340426 (-170 2807);
PAINT SKYBLUE (-170 2807);
DISPLAY INVISIBLE (-170 2807);
FORCEPROP 1 LAST PATH I38
J 0
(-75 2875);
DISPLAY 0.872340 (-75 2875);
PAINT AQUA (-75 2875);
DISPLAY INVISIBLE (-75 2875);
FORCEADD OFFPAGE..5
R 2
(-275 3250);
FORCEPROP 2 LAST $XR0 223 
J 0
(-86 3250);
DISPLAY 0.638298 (-86 3250);
PAINT MONO (-86 3250);
FORCEPROP 1 LAST COMMENT_BODY TRUE
J 2
(-375 3175);
DISPLAY 1.170213 (-375 3175);
PAINT GREEN (-375 3175);
DISPLAY INVISIBLE (-375 3175);
FORCEPROP 1 LAST OFFPAGE TRUE
J 2
(-600 3125);
DISPLAY 1.170213 (-600 3125);
PAINT GREEN (-600 3125);
DISPLAY INVISIBLE (-600 3125);
FORCEPROP 2 LAST CDS_LIB mstr_standard
J 0
(-275 3250);
PAINT MONO (-275 3250);
DISPLAY INVISIBLE (-275 3250);
FORCEPROP 2 LAST PATH I39
J 0
(-75 3300);
DISPLAY 1.021277 (-75 3300);
PAINT ORANGE (-75 3300);
DISPLAY INVISIBLE (-75 3300);
FORCEADD OFFPAGE..4
(-275 3600);
FORCEPROP 2 LAST $XR0 223 
J 0
(-89 3600);
DISPLAY 0.638298 (-89 3600);
PAINT MONO (-89 3600);
FORCEPROP 1 LAST COMMENT_BODY TRUE
J 0
(-300 3500);
DISPLAY 0.680851 (-300 3500);
PAINT PEACH (-300 3500);
DISPLAY INVISIBLE (-300 3500);
FORCEPROP 1 LAST OFFPAGE TRUE
J 0
(50 3475);
DISPLAY 0.680851 (50 3475);
PAINT GREEN (50 3475);
DISPLAY INVISIBLE (50 3475);
FORCEPROP 2 LAST CDS_LIB mstr_standard
J 0
(-275 3600);
PAINT MONO (-275 3600);
DISPLAY INVISIBLE (-275 3600);
FORCEPROP 2 LAST PATH I40
J 0
(-75 3650);
DISPLAY 1.021277 (-75 3650);
PAINT ORANGE (-75 3650);
DISPLAY INVISIBLE (-75 3650);
FORCEADD OFFPAGE..5
R 2
(-275 3300);
FORCEPROP 2 LAST $XR0 223 
J 0
(-86 3300);
DISPLAY 0.638298 (-86 3300);
PAINT MONO (-86 3300);
FORCEPROP 1 LAST COMMENT_BODY TRUE
J 2
(-375 3225);
DISPLAY 1.170213 (-375 3225);
PAINT GREEN (-375 3225);
DISPLAY INVISIBLE (-375 3225);
FORCEPROP 1 LAST OFFPAGE TRUE
J 2
(-600 3175);
DISPLAY 1.170213 (-600 3175);
PAINT GREEN (-600 3175);
DISPLAY INVISIBLE (-600 3175);
FORCEPROP 2 LAST CDS_LIB mstr_standard
J 0
(-275 3300);
PAINT MONO (-275 3300);
DISPLAY INVISIBLE (-275 3300);
FORCEPROP 2 LAST PATH I41
J 0
(-75 3350);
DISPLAY 1.021277 (-75 3350);
PAINT ORANGE (-75 3350);
DISPLAY INVISIBLE (-75 3350);
FORCEADD CAP..1
R 1
(-1725 3550);
FORCEPROP 1 LAST VALUE 47.0PF
J 0
(-1875 3400);
DISPLAY 0.617021 (-1875 3400);
PAINT SKYBLUE (-1875 3400);
FORCEPROP 1 LAST VOLTAGE 50V
J 0
(-1875 3350);
DISPLAY 0.617021 (-1875 3350);
PAINT SKYBLUE (-1875 3350);
FORCEPROP 1 LAST LOCATION C12W3
J 0
(-1875 3450);
DISPLAY 0.617021 (-1875 3450);
PAINT AQUA (-1875 3450);
FORCEPROP 1 LAST TOLERANCE 5%
J 0
(-1875 3300);
DISPLAY 0.617021 (-1875 3300);
PAINT SKYBLUE (-1875 3300);
FORCEPROP 1 LASTPIN (-1825 3550) $PN 1
J 0
(-1855 3560);
DISPLAY 0.617021 (-1855 3560);
PAINT MONO (-1855 3560);
FORCEPROP 1 LASTPIN (-1625 3550) $PN 2
J 0
(-1605 3560);
DISPLAY 0.617021 (-1605 3560);
PAINT MONO (-1605 3560);
FORCEPROP 1 LAST PACK_TYPE 0402LF
J 0
(-1700 3350);
DISPLAY 0.617021 (-1700 3350);
PAINT SKYBLUE (-1700 3350);
FORCEPROP 1 LAST PART_NUMBER A36095-025
J 0
(-1700 3400);
DISPLAY 0.617021 (-1700 3400);
PAINT BLUE (-1700 3400);
FORCEPROP 1 LAST MATERIAL COG
J 0
(-1700 3450);
DISPLAY 0.617021 (-1700 3450);
PAINT SKYBLUE (-1700 3450);
FORCEPROP 2 LAST ROOM BMC_VOLT_MONITOR
R 1
J 0
(-1875 3600);
DISPLAY 1.021277 (-1875 3600);
PAINT ORANGE (-1875 3600);
DISPLAY INVISIBLE (-1875 3600);
FORCEPROP 2 LAST SEC 1
R 1
J 0
(-1925 3600);
DISPLAY 0.936170 (-1925 3600);
PAINT MONO (-1925 3600);
DISPLAY INVISIBLE (-1925 3600);
FORCEPROP 2 LAST SEC_TYPE 0402LF
R 1
J 0
(-1925 3600);
PAINT MONO (-1925 3600);
DISPLAY INVISIBLE (-1925 3600);
FORCEPROP 2 LAST CDS_LIB mstr_discrete
R 1
J 0
(-1725 3550);
DISPLAY 1.361702 (-1725 3550);
PAINT ORANGE (-1725 3550);
DISPLAY INVISIBLE (-1725 3550);
FORCEPROP 2 LAST BOM_COST SM_HM
R 1
J 0
(-1925 3600);
DISPLAY 1.021277 (-1925 3600);
PAINT ORANGE (-1925 3600);
DISPLAY INVISIBLE (-1925 3600);
FORCEPROP 2 LAST CDS_LOCATION C12W3
R 1
J 0
(-1825 3600);
DISPLAY 0.617021 (-1825 3600);
PAINT AQUA (-1825 3600);
DISPLAY INVISIBLE (-1825 3600);
FORCEPROP 0 LAST CDS_SEC 1
R 1
J 0
(-1850 3500);
PAINT MONO (-1850 3500);
DISPLAY INVISIBLE (-1850 3500);
FORCEPROP 1 LAST PATH I42
R 1
J 0
(-1875 3600);
DISPLAY 0.978723 (-1875 3600);
PAINT WHITE (-1875 3600);
DISPLAY INVISIBLE (-1875 3600);
FORCEADD BSL308C-H6327-GP..1
(-3250 4100);
FORCEPROP 1 LAST LOCATION Q12W1
J 0
(-3375 4375);
DISPLAY 0.617021 (-3375 4375);
PAINT GREEN (-3375 4375);
FORCEPROP 2 LASTPIN (-3525 3900) $PN 3
J 2
(-3535 3910);
DISPLAY 0.808511 (-3535 3910);
PAINT ORANGE (-3535 3910);
FORCEPROP 2 LASTPIN (-2975 4300) $PN 6
J 0
(-2965 4310);
DISPLAY 0.808511 (-2965 4310);
PAINT ORANGE (-2965 4310);
FORCEPROP 2 LASTPIN (-2975 4100) $PN 5
J 0
(-2965 4110);
DISPLAY 0.808511 (-2965 4110);
PAINT ORANGE (-2965 4110);
FORCEPROP 1 LAST VALUE BSL308C-H6327-GP
J 0
(-3375 3800);
DISPLAY 0.617021 (-3375 3800);
PAINT GREEN (-3375 3800);
FORCEPROP 2 LASTPIN (-2975 3900) $PN 4
J 0
(-2965 3910);
DISPLAY 0.808511 (-2965 3910);
PAINT ORANGE (-2965 3910);
FORCEPROP 2 LASTPIN (-3525 4100) $PN 2
J 2
(-3535 4110);
DISPLAY 0.808511 (-3535 4110);
PAINT ORANGE (-3535 4110);
FORCEPROP 2 LASTPIN (-3525 4300) $PN 1
J 2
(-3535 4310);
DISPLAY 0.808511 (-3535 4310);
PAINT ORANGE (-3535 4310);
FORCEPROP 1 LAST PART_NUMBER 075.00308.007C
J 0
(-3250 4100);
DISPLAY 0.617021 (-3250 4100);
PAINT GREEN (-3250 4100);
DISPLAY INVISIBLE (-3250 4100);
FORCEPROP 2 LAST CDS_LIB w_hdl
J 0
(-3250 4100);
PAINT MONO (-3250 4100);
DISPLAY INVISIBLE (-3250 4100);
FORCEPROP 1 LAST CDS_LMAN_SYM_OUTLINE -125,250,125,-250
J 0
(-3250 4100);
DISPLAY 0.468085 (-3250 4100);
PAINT GREEN (-3250 4100);
DISPLAY INVISIBLE (-3250 4100);
FORCEPROP 2 LAST SEC_TYPE DISCRET-GB1
J 0
(-3375 4425);
DISPLAY 1.021277 (-3375 4425);
PAINT ORANGE (-3375 4425);
DISPLAY INVISIBLE (-3375 4425);
FORCEPROP 2 LAST SEC 1
J 0
(-3375 4425);
DISPLAY 0.680851 (-3375 4425);
PAINT MONO (-3375 4425);
DISPLAY INVISIBLE (-3375 4425);
FORCEPROP 1 LAST PACK_TYPE DISCRET-GB1
J 0
(-3250 4100);
DISPLAY 0.617021 (-3250 4100);
PAINT GREEN (-3250 4100);
DISPLAY INVISIBLE (-3250 4100);
FORCEPROP 0 LAST CDS_LOCATION Q12W1
J 0
(-3375 4425);
PAINT MONO (-3375 4425);
DISPLAY INVISIBLE (-3375 4425);
FORCEPROP 0 LAST CDS_SEC 1
J 0
(-3375 4425);
PAINT MONO (-3375 4425);
DISPLAY INVISIBLE (-3375 4425);
FORCEPROP 1 LAST PATH I43
J 0
(-3250 4100);
DISPLAY 0.617021 (-3250 4100);
PAINT GREEN (-3250 4100);
DISPLAY INVISIBLE (-3250 4100);
FORCEADD GND..1
(-2925 4000);
FORCEPROP 3 LASTPIN (-2925 4050) SIG_NAME GND\g
J 0
(-2915 4060);
DISPLAY 0.659574 (-2915 4060);
PAINT MONO (-2915 4060);
DISPLAY INVISIBLE (-2915 4060);
FORCEPROP 1 LAST HDL_POWER GND
J 0
(-2925 4150);
DISPLAY 1.170213 (-2925 4150);
PAINT GREEN (-2925 4150);
DISPLAY INVISIBLE (-2925 4150);
FORCEPROP 1 LAST BODY_TYPE PLUMBING
J 0
(-2970 3957);
DISPLAY 0.340426 (-2970 3957);
PAINT GREEN (-2970 3957);
DISPLAY INVISIBLE (-2970 3957);
FORCEPROP 1 LAST VOLTAGE 0.0V
J 0
(-2970 3957);
DISPLAY 0.340426 (-2970 3957);
PAINT SKYBLUE (-2970 3957);
DISPLAY INVISIBLE (-2970 3957);
FORCEPROP 1 LAST SIZE 1B
J 0
(-2850 3950);
DISPLAY 1.170213 (-2850 3950);
PAINT AQUA (-2850 3950);
DISPLAY INVISIBLE (-2850 3950);
FORCEPROP 2 LAST CDS_LIB mstr_symbols
J 0
(-2925 4000);
PAINT ORANGE (-2925 4000);
DISPLAY INVISIBLE (-2925 4000);
FORCEPROP 1 LAST PATH I44
J 0
(-2850 4000);
DISPLAY 0.872340 (-2850 4000);
PAINT AQUA (-2850 4000);
DISPLAY INVISIBLE (-2850 4000);
FORCEADD RES..2
(-2725 4500);
FORCEPROP 1 LAST PART_NUMBER G22026-050
J 0
(-2685 4375);
DISPLAY 0.617021 (-2685 4375);
PAINT BLUE (-2685 4375);
FORCEPROP 1 LAST PACK_TYPE 0603
J 0
(-2685 4325);
DISPLAY 0.617021 (-2685 4325);
PAINT SKYBLUE (-2685 4325);
FORCEPROP 1 LAST WATTAGE 1/10W
J 0
(-2685 4475);
DISPLAY 0.617021 (-2685 4475);
PAINT SKYBLUE (-2685 4475);
FORCEPROP 1 LAST TOLERANCE 1%
J 0
(-2680 4525);
DISPLAY 0.617021 (-2680 4525);
PAINT SKYBLUE (-2680 4525);
FORCEPROP 1 LAST MATERIAL CHIP
J 0
(-2685 4425);
DISPLAY 0.617021 (-2685 4425);
PAINT SKYBLUE (-2685 4425);
FORCEPROP 1 LASTPIN (-2725 4400) $PN 2
J 0
(-2720 4410);
DISPLAY 0.617021 (-2720 4410);
PAINT ORANGE (-2720 4410);
FORCEPROP 1 LASTPIN (-2725 4600) $PN 1
J 0
(-2720 4562);
DISPLAY 0.617021 (-2720 4562);
PAINT ORANGE (-2720 4562);
FORCEPROP 1 LAST VALUE 100.0K
J 0
(-2680 4575);
DISPLAY 0.617021 (-2680 4575);
PAINT SKYBLUE (-2680 4575);
FORCEPROP 1 LAST LOCATION R12W4
J 0
(-2675 4625);
DISPLAY 0.617021 (-2675 4625);
PAINT AQUA (-2675 4625);
FORCEPROP 2 LAST CDS_LIB mstr_discrete
J 0
(-2725 4500);
PAINT ORANGE (-2725 4500);
DISPLAY INVISIBLE (-2725 4500);
FORCEPROP 2 LAST ROOM CPU0
J 0
(-2650 4600);
DISPLAY 1.021277 (-2650 4600);
PAINT ORANGE (-2650 4600);
DISPLAY INVISIBLE (-2650 4600);
FORCEPROP 2 LAST BOM_COST PROC_SOCKET
J 0
(-2650 4650);
DISPLAY 1.021277 (-2650 4650);
PAINT ORANGE (-2650 4650);
DISPLAY INVISIBLE (-2650 4650);
FORCEPROP 2 LAST SEC 1
J 0
(-2675 4725);
DISPLAY 0.680851 (-2675 4725);
PAINT MONO (-2675 4725);
DISPLAY INVISIBLE (-2675 4725);
FORCEPROP 2 LAST SEC_TYPE 0603
J 0
(-2675 4725);
DISPLAY 1.021277 (-2675 4725);
PAINT ORANGE (-2675 4725);
DISPLAY INVISIBLE (-2675 4725);
FORCEPROP 2 LAST CDS_LOCATION R12W4
J 0
(-2675 4625);
DISPLAY 0.617021 (-2675 4625);
PAINT AQUA (-2675 4625);
DISPLAY INVISIBLE (-2675 4625);
FORCEPROP 0 LAST CDS_SEC 1
J 0
(-2675 4675);
PAINT MONO (-2675 4675);
DISPLAY INVISIBLE (-2675 4675);
FORCEPROP 1 LAST PATH I45
J 0
(-2675 4675);
DISPLAY 0.978723 (-2675 4675);
PAINT WHITE (-2675 4675);
DISPLAY INVISIBLE (-2675 4675);
FORCEADD P12V_STBY..1
(-1975 4950);
FORCEPROP 3 LASTPIN (-1975 4900) SIG_NAME P12V_STBY\g
J 0
(-1965 4910);
DISPLAY 0.659574 (-1965 4910);
PAINT MONO (-1965 4910);
DISPLAY INVISIBLE (-1965 4910);
FORCEPROP 1 LAST HDL_POWER P12V_STBY
J 0
(-2275 4825);
DISPLAY 0.872340 (-2275 4825);
PAINT ORANGE (-2275 4825);
DISPLAY INVISIBLE (-2275 4825);
FORCEPROP 1 LAST BODY_TYPE PLUMBING
J 0
(-2020 4907);
DISPLAY 0.340426 (-2020 4907);
PAINT GREEN (-2020 4907);
DISPLAY INVISIBLE (-2020 4907);
FORCEPROP 1 LAST VOLTAGE 12.0V
J 0
(-2020 4907);
DISPLAY 0.340426 (-2020 4907);
PAINT SKYBLUE (-2020 4907);
DISPLAY INVISIBLE (-2020 4907);
FORCEPROP 1 LAST SIZE 1B
J 0
(-1930 4972);
DISPLAY 0.340426 (-1930 4972);
PAINT GREEN (-1930 4972);
DISPLAY INVISIBLE (-1930 4972);
FORCEPROP 2 LAST CDS_LIB mstr_symbols
J 0
(-1975 4950);
PAINT ORANGE (-1975 4950);
DISPLAY INVISIBLE (-1975 4950);
FORCEPROP 1 LAST PATH I49
J 0
(-1930 4952);
DISPLAY 0.340426 (-1930 4952);
PAINT GREEN (-1930 4952);
DISPLAY INVISIBLE (-1930 4952);
FORCEADD RES..1
(-1725 4800);
FORCEPROP 1 LAST TOLERANCE 1%
J 0
(-1800 4725);
DISPLAY 0.617021 (-1800 4725);
PAINT SKYBLUE (-1800 4725);
FORCEPROP 1 LAST WATTAGE 1W
J 2
(-1625 4725);
DISPLAY 0.617021 (-1625 4725);
PAINT SKYBLUE (-1625 4725);
FORCEPROP 1 LAST PACK_TYPE 1206
J 0
(-1500 4725);
DISPLAY 0.617021 (-1500 4725);
PAINT SKYBLUE (-1500 4725);
FORCEPROP 1 LASTPIN (-1825 4800) $PN 1
J 0
(-1813 4812);
DISPLAY 0.617021 (-1813 4812);
PAINT ORANGE (-1813 4812);
FORCEPROP 1 LAST LOCATION R1F3
J 0
(-1775 4850);
DISPLAY 0.617021 (-1775 4850);
PAINT AQUA (-1775 4850);
FORCEPROP 1 LASTPIN (-1625 4800) $PN 2
J 0
(-1663 4812);
DISPLAY 0.617021 (-1663 4812);
PAINT ORANGE (-1663 4812);
FORCEPROP 1 LAST MATERIAL CHIP
J 0
(-1600 4725);
DISPLAY 0.617021 (-1600 4725);
PAINT SKYBLUE (-1600 4725);
FORCEPROP 1 LAST PART_NUMBER G52199-004
J 0
(-1775 4900);
DISPLAY 0.617021 (-1775 4900);
PAINT BLUE (-1775 4900);
FORCEPROP 0 LAST NEW_VALUE 0.004 OHM
J 0
(-1800 4950);
DISPLAY 0.638298 (-1800 4950);
PAINT BROWN (-1800 4950);
DISPLAY BOTH (-1800 4950);
FORCEPROP 0 LAST CONFIG 064.R0045.0711
J 0
(-1800 5000);
DISPLAY 0.638298 (-1800 5000);
PAINT BROWN (-1800 5000);
DISPLAY BOTH (-1800 5000);
FORCEPROP 1 LAST VALUE 0.002
J 2
(-1725 4725);
DISPLAY 0.617021 (-1725 4725);
PAINT SKYBLUE (-1725 4725);
DISPLAY INVISIBLE (-1725 4725);
FORCEPROP 2 LAST SEC_TYPE 1206
J 0
(-1775 5000);
DISPLAY 1.021277 (-1775 5000);
PAINT ORANGE (-1775 5000);
DISPLAY INVISIBLE (-1775 5000);
FORCEPROP 2 LAST BOM_COST PVDDQ_ABC_VR
J 0
(-1775 5000);
DISPLAY 1.361702 (-1775 5000);
PAINT ORANGE (-1775 5000);
DISPLAY INVISIBLE (-1775 5000);
FORCEPROP 2 LAST CDS_LIB mstr_discrete
J 0
(-1725 4800);
PAINT ORANGE (-1725 4800);
DISPLAY INVISIBLE (-1725 4800);
FORCEPROP 2 LAST SEC 1
J 0
(-1775 5000);
DISPLAY 0.680851 (-1775 5000);
PAINT MONO (-1775 5000);
DISPLAY INVISIBLE (-1775 5000);
FORCEPROP 2 LAST ROOM PVDDQ_ABC_PWR_VR
J 0
(-1775 4900);
DISPLAY 1.361702 (-1775 4900);
PAINT ORANGE (-1775 4900);
DISPLAY INVISIBLE (-1775 4900);
FORCEPROP 2 LAST CDS_LOCATION R1F3
J 0
(-1775 4850);
DISPLAY 0.617021 (-1775 4850);
PAINT AQUA (-1775 4850);
DISPLAY INVISIBLE (-1775 4850);
FORCEPROP 0 LAST CDS_SEC 1
J 0
(-1775 4950);
PAINT MONO (-1775 4950);
DISPLAY INVISIBLE (-1775 4950);
FORCEPROP 1 LAST PATH I50
J 0
(-1775 4950);
DISPLAY 0.978723 (-1775 4950);
PAINT WHITE (-1775 4950);
DISPLAY INVISIBLE (-1775 4950);
FORCEADD GND..1
(-375 4000);
FORCEPROP 3 LASTPIN (-375 4050) SIG_NAME GND\g
J 0
(-365 4060);
DISPLAY 0.659574 (-365 4060);
PAINT MONO (-365 4060);
DISPLAY INVISIBLE (-365 4060);
FORCEPROP 1 LAST HDL_POWER GND
J 0
(-375 4150);
DISPLAY 1.170213 (-375 4150);
PAINT GREEN (-375 4150);
DISPLAY INVISIBLE (-375 4150);
FORCEPROP 1 LAST BODY_TYPE PLUMBING
J 0
(-420 3957);
DISPLAY 0.340426 (-420 3957);
PAINT GREEN (-420 3957);
DISPLAY INVISIBLE (-420 3957);
FORCEPROP 2 LAST CDS_LIB mstr_symbols
J 0
(-375 4000);
PAINT ORANGE (-375 4000);
DISPLAY INVISIBLE (-375 4000);
FORCEPROP 1 LAST SIZE 1B
J 0
(-300 3950);
DISPLAY 1.170213 (-300 3950);
PAINT AQUA (-300 3950);
DISPLAY INVISIBLE (-300 3950);
FORCEPROP 1 LAST VOLTAGE 0.0V
J 0
(-420 3957);
DISPLAY 0.340426 (-420 3957);
PAINT SKYBLUE (-420 3957);
DISPLAY INVISIBLE (-420 3957);
FORCEPROP 1 LAST PATH I52
J 0
(-300 4000);
DISPLAY 0.872340 (-300 4000);
PAINT AQUA (-300 4000);
DISPLAY INVISIBLE (-300 4000);
FORCEADD RES..2
(-175 4500);
FORCEPROP 1 LAST VALUE 100.0K
J 0
(-130 4575);
DISPLAY 0.617021 (-130 4575);
PAINT SKYBLUE (-130 4575);
FORCEPROP 1 LAST PACK_TYPE 0603
J 0
(-135 4325);
DISPLAY 0.617021 (-135 4325);
PAINT SKYBLUE (-135 4325);
FORCEPROP 1 LASTPIN (-175 4400) $PN 2
J 0
(-170 4410);
DISPLAY 0.617021 (-170 4410);
PAINT ORANGE (-170 4410);
FORCEPROP 1 LASTPIN (-175 4600) $PN 1
J 0
(-170 4562);
DISPLAY 0.617021 (-170 4562);
PAINT ORANGE (-170 4562);
FORCEPROP 1 LAST LOCATION R12W14
J 0
(-125 4625);
DISPLAY 0.617021 (-125 4625);
PAINT AQUA (-125 4625);
FORCEPROP 1 LAST WATTAGE 1/10W
J 0
(-135 4475);
DISPLAY 0.617021 (-135 4475);
PAINT SKYBLUE (-135 4475);
FORCEPROP 1 LAST TOLERANCE 1%
J 0
(-130 4525);
DISPLAY 0.617021 (-130 4525);
PAINT SKYBLUE (-130 4525);
FORCEPROP 1 LAST MATERIAL CHIP
J 0
(-135 4425);
DISPLAY 0.617021 (-135 4425);
PAINT SKYBLUE (-135 4425);
FORCEPROP 1 LAST PART_NUMBER G22026-050
J 0
(-135 4375);
DISPLAY 0.617021 (-135 4375);
PAINT BLUE (-135 4375);
FORCEPROP 2 LAST SEC_TYPE 0603
J 0
(-125 4725);
DISPLAY 1.021277 (-125 4725);
PAINT ORANGE (-125 4725);
DISPLAY INVISIBLE (-125 4725);
FORCEPROP 2 LAST SEC 1
J 0
(-125 4725);
DISPLAY 0.680851 (-125 4725);
PAINT MONO (-125 4725);
DISPLAY INVISIBLE (-125 4725);
FORCEPROP 2 LAST BOM_COST PROC_SOCKET
J 0
(-100 4650);
DISPLAY 1.021277 (-100 4650);
PAINT ORANGE (-100 4650);
DISPLAY INVISIBLE (-100 4650);
FORCEPROP 2 LAST ROOM CPU0
J 0
(-100 4600);
DISPLAY 1.021277 (-100 4600);
PAINT ORANGE (-100 4600);
DISPLAY INVISIBLE (-100 4600);
FORCEPROP 2 LAST CDS_LIB mstr_discrete
J 0
(-175 4500);
PAINT ORANGE (-175 4500);
DISPLAY INVISIBLE (-175 4500);
FORCEPROP 2 LAST CDS_LOCATION R12W14
J 0
(-125 4625);
DISPLAY 0.617021 (-125 4625);
PAINT AQUA (-125 4625);
DISPLAY INVISIBLE (-125 4625);
FORCEPROP 0 LAST CDS_SEC 1
J 0
(-125 4675);
PAINT MONO (-125 4675);
DISPLAY INVISIBLE (-125 4675);
FORCEPROP 1 LAST PATH I53
J 0
(-125 4675);
DISPLAY 0.978723 (-125 4675);
PAINT WHITE (-125 4675);
DISPLAY INVISIBLE (-125 4675);
FORCEADD P12V_NVDIMM_GHJ..1
(-125 4950);
FORCEPROP 3 LASTPIN (-125 4900) SIG_NAME P12V_NVDIMM_GHJ\g
J 0
(-115 4910);
DISPLAY 0.659574 (-115 4910);
PAINT MONO (-115 4910);
DISPLAY INVISIBLE (-115 4910);
FORCEPROP 1 LAST HDL_POWER P12V_NVDIMM_GHJ
J 1
(-125 5000);
DISPLAY 0.872340 (-125 5000);
PAINT GREEN (-125 5000);
DISPLAY INVISIBLE (-125 5000);
FORCEPROP 1 LAST BODY_TYPE PLUMBING
J 0
(-170 4907);
DISPLAY 0.340426 (-170 4907);
PAINT GREEN (-170 4907);
DISPLAY INVISIBLE (-170 4907);
FORCEPROP 1 LAST VOLTAGE 12.0
J 0
(-170 4907);
DISPLAY 0.340426 (-170 4907);
PAINT SKYBLUE (-170 4907);
DISPLAY INVISIBLE (-170 4907);
FORCEPROP 2 LAST CDS_LIB mstr_symbols
J 0
(-125 4950);
PAINT ORANGE (-125 4950);
DISPLAY INVISIBLE (-125 4950);
FORCEPROP 1 LAST PATH I54
J 0
(-75 4975);
DISPLAY 0.872340 (-75 4975);
PAINT AQUA (-75 4975);
DISPLAY INVISIBLE (-75 4975);
FORCEADD GND..1
(1325 1100);
FORCEPROP 3 LASTPIN (1325 1150) SIG_NAME GND\g
J 0
(1335 1160);
DISPLAY 0.659574 (1335 1160);
PAINT MONO (1335 1160);
DISPLAY INVISIBLE (1335 1160);
FORCEPROP 1 LAST HDL_POWER GND
J 0
(1325 1250);
DISPLAY 1.170213 (1325 1250);
PAINT GREEN (1325 1250);
DISPLAY INVISIBLE (1325 1250);
FORCEPROP 1 LAST BODY_TYPE PLUMBING
J 0
(1280 1057);
DISPLAY 0.340426 (1280 1057);
PAINT GREEN (1280 1057);
DISPLAY INVISIBLE (1280 1057);
FORCEPROP 2 LAST CDS_LIB mstr_symbols
J 0
(1325 1100);
PAINT ORANGE (1325 1100);
DISPLAY INVISIBLE (1325 1100);
FORCEPROP 1 LAST SIZE 1B
J 0
(1400 1050);
DISPLAY 1.170213 (1400 1050);
PAINT AQUA (1400 1050);
DISPLAY INVISIBLE (1400 1050);
FORCEPROP 1 LAST VOLTAGE 0.0V
J 0
(1280 1057);
DISPLAY 0.340426 (1280 1057);
PAINT SKYBLUE (1280 1057);
DISPLAY INVISIBLE (1280 1057);
FORCEPROP 1 LAST PATH I55
J 0
(1400 1100);
DISPLAY 0.872340 (1400 1100);
PAINT AQUA (1400 1100);
DISPLAY INVISIBLE (1400 1100);
FORCEADD CAP..1
(1325 1275);
FORCEPROP 1 LAST PACK_TYPE 0805
J 0
(1375 1075);
DISPLAY 0.617021 (1375 1075);
PAINT SKYBLUE (1375 1075);
FORCEPROP 1 LAST PART_NUMBER G10601-001
J 0
(1375 1125);
DISPLAY 0.617021 (1375 1125);
PAINT BLUE (1375 1125);
FORCEPROP 1 LAST MATERIAL X7R
J 0
(1375 1175);
DISPLAY 0.617021 (1375 1175);
PAINT SKYBLUE (1375 1175);
FORCEPROP 1 LAST TOLERANCE 10%
J 0
(1375 1225);
DISPLAY 0.617021 (1375 1225);
PAINT SKYBLUE (1375 1225);
FORCEPROP 1 LAST VALUE 10UF
J 0
(1375 1325);
DISPLAY 0.617021 (1375 1325);
PAINT SKYBLUE (1375 1325);
FORCEPROP 1 LAST LOCATION C9T8
J 0
(1375 1375);
DISPLAY 0.617021 (1375 1375);
PAINT AQUA (1375 1375);
FORCEPROP 1 LASTPIN (1325 1375) $PN 1
J 0
(1335 1355);
DISPLAY 0.617021 (1335 1355);
PAINT WHITE (1335 1355);
FORCEPROP 1 LASTPIN (1325 1175) $PN 2
J 0
(1335 1155);
DISPLAY 0.617021 (1335 1155);
PAINT WHITE (1335 1155);
FORCEPROP 1 LAST VOLTAGE 16V
J 0
(1375 1275);
DISPLAY 0.617021 (1375 1275);
PAINT SKYBLUE (1375 1275);
FORCEPROP 0 LAST ROOM PVDDQ_GHJ_PWR_VR
J 0
(1375 1425);
DISPLAY 1.021277 (1375 1425);
PAINT ORANGE (1375 1425);
DISPLAY INVISIBLE (1375 1425);
FORCEPROP 2 LAST CDS_LOCATION C9T8
J 0
(1375 1375);
DISPLAY 0.617021 (1375 1375);
PAINT AQUA (1375 1375);
DISPLAY INVISIBLE (1375 1375);
FORCEPROP 2 LAST $SEC 1
J 0
(1375 1475);
DISPLAY 0.914894 (1375 1475);
PAINT MONO (1375 1475);
DISPLAY INVISIBLE (1375 1475);
FORCEPROP 2 LAST CDS_SEC 1
J 0
(1375 1475);
DISPLAY 1.361702 (1375 1475);
PAINT ORANGE (1375 1475);
DISPLAY INVISIBLE (1375 1475);
FORCEPROP 2 LAST CDS_LIB mstr_discrete
J 0
(1325 1275);
PAINT ORANGE (1325 1275);
DISPLAY INVISIBLE (1325 1275);
FORCEPROP 1 LAST PATH I56
J 0
(1375 1425);
DISPLAY 0.978723 (1375 1425);
PAINT WHITE (1375 1425);
DISPLAY INVISIBLE (1375 1425);
FORCEADD P12V_NVDIMM_GHJ..1
(1325 1450);
FORCEPROP 3 LASTPIN (1325 1400) SIG_NAME P12V_NVDIMM_GHJ\g
J 0
(1335 1410);
DISPLAY 0.659574 (1335 1410);
PAINT MONO (1335 1410);
DISPLAY INVISIBLE (1335 1410);
FORCEPROP 1 LAST HDL_POWER P12V_NVDIMM_GHJ
J 1
(1325 1500);
DISPLAY 0.872340 (1325 1500);
PAINT GREEN (1325 1500);
DISPLAY INVISIBLE (1325 1500);
FORCEPROP 1 LAST BODY_TYPE PLUMBING
J 0
(1280 1407);
DISPLAY 0.340426 (1280 1407);
PAINT GREEN (1280 1407);
DISPLAY INVISIBLE (1280 1407);
FORCEPROP 2 LAST CDS_LIB mstr_symbols
J 0
(1325 1450);
PAINT ORANGE (1325 1450);
DISPLAY INVISIBLE (1325 1450);
FORCEPROP 1 LAST VOLTAGE 12.0
J 0
(1280 1407);
DISPLAY 0.340426 (1280 1407);
PAINT SKYBLUE (1280 1407);
DISPLAY INVISIBLE (1280 1407);
FORCEPROP 1 LAST PATH I57
J 0
(1375 1475);
DISPLAY 0.872340 (1375 1475);
PAINT AQUA (1375 1475);
DISPLAY INVISIBLE (1375 1475);
FORCEADD GND..1
(1325 1675);
FORCEPROP 3 LASTPIN (1325 1725) SIG_NAME GND\g
J 0
(1335 1735);
DISPLAY 0.659574 (1335 1735);
PAINT MONO (1335 1735);
DISPLAY INVISIBLE (1335 1735);
FORCEPROP 1 LAST HDL_POWER GND
J 0
(1325 1825);
DISPLAY 1.170213 (1325 1825);
PAINT GREEN (1325 1825);
DISPLAY INVISIBLE (1325 1825);
FORCEPROP 1 LAST BODY_TYPE PLUMBING
J 0
(1280 1632);
DISPLAY 0.340426 (1280 1632);
PAINT GREEN (1280 1632);
DISPLAY INVISIBLE (1280 1632);
FORCEPROP 1 LAST SIZE 1B
J 0
(1400 1625);
DISPLAY 1.170213 (1400 1625);
PAINT AQUA (1400 1625);
DISPLAY INVISIBLE (1400 1625);
FORCEPROP 2 LAST CDS_LIB mstr_symbols
J 0
(1325 1675);
PAINT ORANGE (1325 1675);
DISPLAY INVISIBLE (1325 1675);
FORCEPROP 1 LAST VOLTAGE 0.0V
J 0
(1280 1632);
DISPLAY 0.340426 (1280 1632);
PAINT SKYBLUE (1280 1632);
DISPLAY INVISIBLE (1280 1632);
FORCEPROP 1 LAST PATH I58
J 0
(1400 1675);
DISPLAY 0.872340 (1400 1675);
PAINT AQUA (1400 1675);
DISPLAY INVISIBLE (1400 1675);
FORCEADD GND..1
(2175 1075);
FORCEPROP 3 LASTPIN (2175 1125) SIG_NAME GND\g
J 0
(2185 1135);
DISPLAY 0.659574 (2185 1135);
PAINT MONO (2185 1135);
DISPLAY INVISIBLE (2185 1135);
FORCEPROP 1 LAST HDL_POWER GND
J 0
(2175 1225);
DISPLAY 1.170213 (2175 1225);
PAINT GREEN (2175 1225);
DISPLAY INVISIBLE (2175 1225);
FORCEPROP 1 LAST BODY_TYPE PLUMBING
J 0
(2130 1032);
DISPLAY 0.340426 (2130 1032);
PAINT GREEN (2130 1032);
DISPLAY INVISIBLE (2130 1032);
FORCEPROP 1 LAST SIZE 1B
J 0
(2250 1025);
DISPLAY 1.170213 (2250 1025);
PAINT AQUA (2250 1025);
DISPLAY INVISIBLE (2250 1025);
FORCEPROP 2 LAST CDS_LIB mstr_symbols
J 0
(2175 1075);
PAINT ORANGE (2175 1075);
DISPLAY INVISIBLE (2175 1075);
FORCEPROP 1 LAST VOLTAGE 0.0V
J 0
(2130 1032);
DISPLAY 0.340426 (2130 1032);
PAINT SKYBLUE (2130 1032);
DISPLAY INVISIBLE (2130 1032);
FORCEPROP 1 LAST PATH I59
J 0
(2250 1075);
DISPLAY 0.872340 (2250 1075);
PAINT AQUA (2250 1075);
DISPLAY INVISIBLE (2250 1075);
FORCEADD RES..1
(-4275 2700);
FORCEPROP 1 LASTPIN (-4375 2700) $PN 1
J 0
(-4363 2712);
DISPLAY 0.617021 (-4363 2712);
PAINT ORANGE (-4363 2712);
FORCEPROP 1 LAST LOCATION R4B12
J 0
(-4325 2750);
DISPLAY 0.617021 (-4325 2750);
PAINT AQUA (-4325 2750);
FORCEPROP 1 LASTPIN (-4175 2700) $PN 2
J 0
(-4213 2712);
DISPLAY 0.617021 (-4213 2712);
PAINT ORANGE (-4213 2712);
FORCEPROP 1 LAST PART_NUMBER G52199-004
J 0
(-4325 2800);
DISPLAY 0.617021 (-4325 2800);
PAINT BLUE (-4325 2800);
FORCEPROP 1 LAST PACK_TYPE 1206
J 0
(-4075 2625);
DISPLAY 0.617021 (-4075 2625);
PAINT SKYBLUE (-4075 2625);
FORCEPROP 1 LAST MATERIAL CHIP
J 0
(-4175 2625);
DISPLAY 0.617021 (-4175 2625);
PAINT SKYBLUE (-4175 2625);
FORCEPROP 1 LAST WATTAGE 1W
J 2
(-4200 2625);
DISPLAY 0.617021 (-4200 2625);
PAINT SKYBLUE (-4200 2625);
FORCEPROP 1 LAST TOLERANCE 1%
J 0
(-4350 2625);
DISPLAY 0.617021 (-4350 2625);
PAINT SKYBLUE (-4350 2625);
FORCEPROP 0 LAST CONFIG 064.R0045.0711
J 0
(-4350 2900);
DISPLAY 0.638298 (-4350 2900);
PAINT BROWN (-4350 2900);
DISPLAY BOTH (-4350 2900);
FORCEPROP 0 LAST NEW_VALUE 0.004 OHM
J 0
(-4350 2850);
DISPLAY 0.638298 (-4350 2850);
PAINT BROWN (-4350 2850);
DISPLAY BOTH (-4350 2850);
FORCEPROP 1 LAST PATH I6
J 0
(-4325 2850);
DISPLAY 0.978723 (-4325 2850);
PAINT WHITE (-4325 2850);
DISPLAY INVISIBLE (-4325 2850);
FORCEPROP 0 LAST CDS_SEC 1
J 0
(-4325 2850);
PAINT MONO (-4325 2850);
DISPLAY INVISIBLE (-4325 2850);
FORCEPROP 2 LAST CDS_LOCATION R4B12
J 0
(-4325 2750);
DISPLAY 0.617021 (-4325 2750);
PAINT AQUA (-4325 2750);
DISPLAY INVISIBLE (-4325 2750);
FORCEPROP 2 LAST ROOM PVDDQ_ABC_PWR_VR
J 0
(-4325 2800);
DISPLAY 1.361702 (-4325 2800);
PAINT ORANGE (-4325 2800);
DISPLAY INVISIBLE (-4325 2800);
FORCEPROP 2 LAST SEC 1
J 0
(-4325 2900);
DISPLAY 0.680851 (-4325 2900);
PAINT MONO (-4325 2900);
DISPLAY INVISIBLE (-4325 2900);
FORCEPROP 2 LAST CDS_LIB mstr_discrete
J 0
(-4275 2700);
PAINT ORANGE (-4275 2700);
DISPLAY INVISIBLE (-4275 2700);
FORCEPROP 2 LAST BOM_COST PVDDQ_ABC_VR
J 0
(-4325 2900);
DISPLAY 1.361702 (-4325 2900);
PAINT ORANGE (-4325 2900);
DISPLAY INVISIBLE (-4325 2900);
FORCEPROP 2 LAST SEC_TYPE 1206
J 0
(-4325 2900);
DISPLAY 1.021277 (-4325 2900);
PAINT ORANGE (-4325 2900);
DISPLAY INVISIBLE (-4325 2900);
FORCEPROP 1 LAST VALUE 0.002
J 2
(-4300 2625);
DISPLAY 0.617021 (-4300 2625);
PAINT SKYBLUE (-4300 2625);
DISPLAY INVISIBLE (-4300 2625);
FORCEADD CAP..1
(2175 1275);
FORCEPROP 1 LAST PART_NUMBER G10601-001
J 0
(2225 1125);
DISPLAY 0.617021 (2225 1125);
PAINT BLUE (2225 1125);
FORCEPROP 1 LAST PACK_TYPE 0805
J 0
(2225 1075);
DISPLAY 0.617021 (2225 1075);
PAINT SKYBLUE (2225 1075);
FORCEPROP 1 LAST VALUE 10UF
J 0
(2225 1325);
DISPLAY 0.617021 (2225 1325);
PAINT SKYBLUE (2225 1325);
FORCEPROP 1 LAST TOLERANCE 10%
J 0
(2225 1225);
DISPLAY 0.617021 (2225 1225);
PAINT SKYBLUE (2225 1225);
FORCEPROP 1 LAST VOLTAGE 16V
J 0
(2225 1275);
DISPLAY 0.617021 (2225 1275);
PAINT SKYBLUE (2225 1275);
FORCEPROP 1 LASTPIN (2175 1375) $PN 1
J 0
(2185 1355);
DISPLAY 0.617021 (2185 1355);
PAINT WHITE (2185 1355);
FORCEPROP 1 LAST MATERIAL X7R
J 0
(2225 1175);
DISPLAY 0.617021 (2225 1175);
PAINT SKYBLUE (2225 1175);
FORCEPROP 1 LASTPIN (2175 1175) $PN 2
J 0
(2185 1155);
DISPLAY 0.617021 (2185 1155);
PAINT WHITE (2185 1155);
FORCEPROP 1 LAST LOCATION C1A4
J 0
(2225 1375);
DISPLAY 0.617021 (2225 1375);
PAINT AQUA (2225 1375);
FORCEPROP 0 LAST ROOM PVDDQ_KLM_PWR_VR
J 0
(2225 1425);
DISPLAY 1.021277 (2225 1425);
PAINT ORANGE (2225 1425);
DISPLAY INVISIBLE (2225 1425);
FORCEPROP 2 LAST CDS_LOCATION C1A4
J 0
(2225 1375);
DISPLAY 0.617021 (2225 1375);
PAINT AQUA (2225 1375);
DISPLAY INVISIBLE (2225 1375);
FORCEPROP 2 LAST $SEC 1
J 0
(2225 1475);
DISPLAY 0.914894 (2225 1475);
PAINT MONO (2225 1475);
DISPLAY INVISIBLE (2225 1475);
FORCEPROP 2 LAST CDS_SEC 1
J 0
(2225 1475);
DISPLAY 1.361702 (2225 1475);
PAINT ORANGE (2225 1475);
DISPLAY INVISIBLE (2225 1475);
FORCEPROP 2 LAST CDS_LIB mstr_discrete
J 0
(2175 1275);
PAINT ORANGE (2175 1275);
DISPLAY INVISIBLE (2175 1275);
FORCEPROP 1 LAST PATH I60
J 0
(2225 1425);
DISPLAY 0.978723 (2225 1425);
PAINT WHITE (2225 1425);
DISPLAY INVISIBLE (2225 1425);
FORCEADD P12V_NVDIMM_KLM..1
(2175 1450);
FORCEPROP 3 LASTPIN (2175 1400) SIG_NAME P12V_NVDIMM_KLM\g
J 0
(2185 1410);
DISPLAY 0.659574 (2185 1410);
PAINT MONO (2185 1410);
DISPLAY INVISIBLE (2185 1410);
FORCEPROP 1 LAST HDL_POWER P12V_NVDIMM_KLM
J 1
(2175 1500);
DISPLAY 0.872340 (2175 1500);
PAINT GREEN (2175 1500);
DISPLAY INVISIBLE (2175 1500);
FORCEPROP 1 LAST BODY_TYPE PLUMBING
J 0
(2130 1407);
DISPLAY 0.340426 (2130 1407);
PAINT GREEN (2130 1407);
DISPLAY INVISIBLE (2130 1407);
FORCEPROP 2 LAST CDS_LIB mstr_symbols
J 0
(2175 1450);
PAINT ORANGE (2175 1450);
DISPLAY INVISIBLE (2175 1450);
FORCEPROP 1 LAST VOLTAGE 12.0
J 0
(2130 1407);
DISPLAY 0.340426 (2130 1407);
PAINT SKYBLUE (2130 1407);
DISPLAY INVISIBLE (2130 1407);
FORCEPROP 1 LAST PATH I61
J 0
(2225 1475);
DISPLAY 0.872340 (2225 1475);
PAINT AQUA (2225 1475);
DISPLAY INVISIBLE (2225 1475);
FORCEADD GND..1
(2175 1650);
FORCEPROP 3 LASTPIN (2175 1700) SIG_NAME GND\g
J 0
(2185 1710);
DISPLAY 0.659574 (2185 1710);
PAINT MONO (2185 1710);
DISPLAY INVISIBLE (2185 1710);
FORCEPROP 1 LAST HDL_POWER GND
J 0
(2175 1800);
DISPLAY 1.170213 (2175 1800);
PAINT GREEN (2175 1800);
DISPLAY INVISIBLE (2175 1800);
FORCEPROP 1 LAST BODY_TYPE PLUMBING
J 0
(2130 1607);
DISPLAY 0.340426 (2130 1607);
PAINT GREEN (2130 1607);
DISPLAY INVISIBLE (2130 1607);
FORCEPROP 1 LAST SIZE 1B
J 0
(2250 1600);
DISPLAY 1.170213 (2250 1600);
PAINT AQUA (2250 1600);
DISPLAY INVISIBLE (2250 1600);
FORCEPROP 2 LAST CDS_LIB mstr_symbols
J 0
(2175 1650);
PAINT ORANGE (2175 1650);
DISPLAY INVISIBLE (2175 1650);
FORCEPROP 1 LAST VOLTAGE 0.0V
J 0
(2130 1607);
DISPLAY 0.340426 (2130 1607);
PAINT SKYBLUE (2130 1607);
DISPLAY INVISIBLE (2130 1607);
FORCEPROP 1 LAST PATH I62
J 0
(2250 1650);
DISPLAY 0.872340 (2250 1650);
PAINT AQUA (2250 1650);
DISPLAY INVISIBLE (2250 1650);
FORCEADD CAP..1
(1325 1850);
FORCEPROP 1 LAST PART_NUMBER G10601-001
J 0
(1375 1700);
DISPLAY 0.617021 (1375 1700);
PAINT BLUE (1375 1700);
FORCEPROP 1 LAST PACK_TYPE 0805
J 0
(1375 1650);
DISPLAY 0.617021 (1375 1650);
PAINT SKYBLUE (1375 1650);
FORCEPROP 1 LASTPIN (1325 1950) $PN 1
J 0
(1335 1930);
DISPLAY 0.617021 (1335 1930);
PAINT WHITE (1335 1930);
FORCEPROP 1 LAST TOLERANCE 10%
J 0
(1375 1800);
DISPLAY 0.617021 (1375 1800);
PAINT SKYBLUE (1375 1800);
FORCEPROP 1 LASTPIN (1325 1750) $PN 2
J 0
(1335 1730);
DISPLAY 0.617021 (1335 1730);
PAINT WHITE (1335 1730);
FORCEPROP 1 LAST MATERIAL X7R
J 0
(1375 1750);
DISPLAY 0.617021 (1375 1750);
PAINT SKYBLUE (1375 1750);
FORCEPROP 1 LAST VOLTAGE 16V
J 0
(1375 1850);
DISPLAY 0.617021 (1375 1850);
PAINT SKYBLUE (1375 1850);
FORCEPROP 1 LAST LOCATION C9U11
J 0
(1375 1950);
DISPLAY 0.617021 (1375 1950);
PAINT AQUA (1375 1950);
FORCEPROP 1 LAST VALUE 10UF
J 0
(1375 1900);
DISPLAY 0.617021 (1375 1900);
PAINT SKYBLUE (1375 1900);
FORCEPROP 0 LAST ROOM PVDDQ_GHJ_PWR_VR
J 0
(1375 2000);
DISPLAY 1.021277 (1375 2000);
PAINT ORANGE (1375 2000);
DISPLAY INVISIBLE (1375 2000);
FORCEPROP 2 LAST CDS_LOCATION C9U11
J 0
(1375 1950);
DISPLAY 0.617021 (1375 1950);
PAINT AQUA (1375 1950);
DISPLAY INVISIBLE (1375 1950);
FORCEPROP 2 LAST $SEC 1
J 0
(1375 2050);
DISPLAY 0.914894 (1375 2050);
PAINT MONO (1375 2050);
DISPLAY INVISIBLE (1375 2050);
FORCEPROP 2 LAST CDS_SEC 1
J 0
(1375 2050);
DISPLAY 1.361702 (1375 2050);
PAINT ORANGE (1375 2050);
DISPLAY INVISIBLE (1375 2050);
FORCEPROP 2 LAST CDS_LIB mstr_discrete
J 0
(1325 1850);
PAINT ORANGE (1325 1850);
DISPLAY INVISIBLE (1325 1850);
FORCEPROP 1 LAST PATH I63
J 0
(1375 2000);
DISPLAY 0.978723 (1375 2000);
PAINT WHITE (1375 2000);
DISPLAY INVISIBLE (1375 2000);
FORCEADD P12V_NVDIMM_GHJ..1
(1325 2025);
FORCEPROP 3 LASTPIN (1325 1975) SIG_NAME P12V_NVDIMM_GHJ\g
J 0
(1335 1985);
DISPLAY 0.659574 (1335 1985);
PAINT MONO (1335 1985);
DISPLAY INVISIBLE (1335 1985);
FORCEPROP 1 LAST HDL_POWER P12V_NVDIMM_GHJ
J 1
(1325 2075);
DISPLAY 0.872340 (1325 2075);
PAINT GREEN (1325 2075);
DISPLAY INVISIBLE (1325 2075);
FORCEPROP 1 LAST BODY_TYPE PLUMBING
J 0
(1280 1982);
DISPLAY 0.340426 (1280 1982);
PAINT GREEN (1280 1982);
DISPLAY INVISIBLE (1280 1982);
FORCEPROP 2 LAST CDS_LIB mstr_symbols
J 0
(1325 2025);
PAINT ORANGE (1325 2025);
DISPLAY INVISIBLE (1325 2025);
FORCEPROP 1 LAST VOLTAGE 12.0
J 0
(1280 1982);
DISPLAY 0.340426 (1280 1982);
PAINT SKYBLUE (1280 1982);
DISPLAY INVISIBLE (1280 1982);
FORCEPROP 1 LAST PATH I64
J 0
(1375 2050);
DISPLAY 0.872340 (1375 2050);
PAINT AQUA (1375 2050);
DISPLAY INVISIBLE (1375 2050);
FORCEADD GND..1
(1325 2325);
FORCEPROP 3 LASTPIN (1325 2375) SIG_NAME GND\g
J 0
(1335 2385);
DISPLAY 0.659574 (1335 2385);
PAINT MONO (1335 2385);
DISPLAY INVISIBLE (1335 2385);
FORCEPROP 1 LAST HDL_POWER GND
J 0
(1325 2475);
DISPLAY 1.170213 (1325 2475);
PAINT GREEN (1325 2475);
DISPLAY INVISIBLE (1325 2475);
FORCEPROP 1 LAST BODY_TYPE PLUMBING
J 0
(1280 2282);
DISPLAY 0.340426 (1280 2282);
PAINT GREEN (1280 2282);
DISPLAY INVISIBLE (1280 2282);
FORCEPROP 2 LAST CDS_LIB mstr_symbols
J 0
(1325 2325);
PAINT ORANGE (1325 2325);
DISPLAY INVISIBLE (1325 2325);
FORCEPROP 1 LAST SIZE 1B
J 0
(1400 2275);
DISPLAY 1.170213 (1400 2275);
PAINT AQUA (1400 2275);
DISPLAY INVISIBLE (1400 2275);
FORCEPROP 1 LAST VOLTAGE 0.0V
J 0
(1280 2282);
DISPLAY 0.340426 (1280 2282);
PAINT SKYBLUE (1280 2282);
DISPLAY INVISIBLE (1280 2282);
FORCEPROP 1 LAST PATH I65
J 0
(1400 2325);
DISPLAY 0.872340 (1400 2325);
PAINT AQUA (1400 2325);
DISPLAY INVISIBLE (1400 2325);
FORCEADD CAP..1
(1325 2500);
FORCEPROP 1 LASTPIN (1325 2600) $PN 1
J 0
(1335 2580);
DISPLAY 0.617021 (1335 2580);
PAINT WHITE (1335 2580);
FORCEPROP 1 LASTPIN (1325 2400) $PN 2
J 0
(1335 2380);
DISPLAY 0.617021 (1335 2380);
PAINT WHITE (1335 2380);
FORCEPROP 1 LAST PACK_TYPE 0805
J 0
(1375 2300);
DISPLAY 0.617021 (1375 2300);
PAINT SKYBLUE (1375 2300);
FORCEPROP 1 LAST PART_NUMBER G10601-001
J 0
(1375 2350);
DISPLAY 0.617021 (1375 2350);
PAINT BLUE (1375 2350);
FORCEPROP 1 LAST MATERIAL X7R
J 0
(1375 2400);
DISPLAY 0.617021 (1375 2400);
PAINT SKYBLUE (1375 2400);
FORCEPROP 1 LAST VOLTAGE 16V
J 0
(1375 2500);
DISPLAY 0.617021 (1375 2500);
PAINT SKYBLUE (1375 2500);
FORCEPROP 1 LAST VALUE 10UF
J 0
(1375 2550);
DISPLAY 0.617021 (1375 2550);
PAINT SKYBLUE (1375 2550);
FORCEPROP 1 LAST LOCATION C9U8
J 0
(1375 2600);
DISPLAY 0.617021 (1375 2600);
PAINT AQUA (1375 2600);
FORCEPROP 1 LAST TOLERANCE 10%
J 0
(1375 2450);
DISPLAY 0.617021 (1375 2450);
PAINT SKYBLUE (1375 2450);
FORCEPROP 0 LAST ROOM PVDDQ_GHJ_PWR_VR
J 0
(1375 2650);
DISPLAY 1.021277 (1375 2650);
PAINT ORANGE (1375 2650);
DISPLAY INVISIBLE (1375 2650);
FORCEPROP 2 LAST CDS_LOCATION C9U8
J 0
(1375 2600);
DISPLAY 0.617021 (1375 2600);
PAINT AQUA (1375 2600);
DISPLAY INVISIBLE (1375 2600);
FORCEPROP 2 LAST $SEC 1
J 0
(1375 2700);
DISPLAY 0.914894 (1375 2700);
PAINT MONO (1375 2700);
DISPLAY INVISIBLE (1375 2700);
FORCEPROP 2 LAST CDS_SEC 1
J 0
(1375 2700);
DISPLAY 1.361702 (1375 2700);
PAINT ORANGE (1375 2700);
DISPLAY INVISIBLE (1375 2700);
FORCEPROP 2 LAST CDS_LIB mstr_discrete
J 0
(1325 2500);
PAINT ORANGE (1325 2500);
DISPLAY INVISIBLE (1325 2500);
FORCEPROP 1 LAST PATH I66
J 0
(1375 2650);
DISPLAY 0.978723 (1375 2650);
PAINT WHITE (1375 2650);
DISPLAY INVISIBLE (1375 2650);
FORCEADD P12V_NVDIMM_GHJ..1
(1325 2675);
FORCEPROP 3 LASTPIN (1325 2625) SIG_NAME P12V_NVDIMM_GHJ\g
J 0
(1335 2635);
DISPLAY 0.659574 (1335 2635);
PAINT MONO (1335 2635);
DISPLAY INVISIBLE (1335 2635);
FORCEPROP 1 LAST HDL_POWER P12V_NVDIMM_GHJ
J 1
(1325 2725);
DISPLAY 0.872340 (1325 2725);
PAINT GREEN (1325 2725);
DISPLAY INVISIBLE (1325 2725);
FORCEPROP 1 LAST BODY_TYPE PLUMBING
J 0
(1280 2632);
DISPLAY 0.340426 (1280 2632);
PAINT GREEN (1280 2632);
DISPLAY INVISIBLE (1280 2632);
FORCEPROP 2 LAST CDS_LIB mstr_symbols
J 0
(1325 2675);
PAINT ORANGE (1325 2675);
DISPLAY INVISIBLE (1325 2675);
FORCEPROP 1 LAST VOLTAGE 12.0
J 0
(1280 2632);
DISPLAY 0.340426 (1280 2632);
PAINT SKYBLUE (1280 2632);
DISPLAY INVISIBLE (1280 2632);
FORCEPROP 1 LAST PATH I67
J 0
(1375 2700);
DISPLAY 0.872340 (1375 2700);
PAINT AQUA (1375 2700);
DISPLAY INVISIBLE (1375 2700);
FORCEADD GND..1
(1325 2975);
FORCEPROP 3 LASTPIN (1325 3025) SIG_NAME GND\g
J 0
(1335 3035);
DISPLAY 0.659574 (1335 3035);
PAINT MONO (1335 3035);
DISPLAY INVISIBLE (1335 3035);
FORCEPROP 1 LAST HDL_POWER GND
J 0
(1325 3125);
DISPLAY 1.170213 (1325 3125);
PAINT GREEN (1325 3125);
DISPLAY INVISIBLE (1325 3125);
FORCEPROP 1 LAST BODY_TYPE PLUMBING
J 0
(1280 2932);
DISPLAY 0.340426 (1280 2932);
PAINT GREEN (1280 2932);
DISPLAY INVISIBLE (1280 2932);
FORCEPROP 2 LAST CDS_LIB mstr_symbols
J 0
(1325 2975);
PAINT ORANGE (1325 2975);
DISPLAY INVISIBLE (1325 2975);
FORCEPROP 1 LAST SIZE 1B
J 0
(1400 2925);
DISPLAY 1.170213 (1400 2925);
PAINT AQUA (1400 2925);
DISPLAY INVISIBLE (1400 2925);
FORCEPROP 1 LAST VOLTAGE 0.0V
J 0
(1280 2932);
DISPLAY 0.340426 (1280 2932);
PAINT SKYBLUE (1280 2932);
DISPLAY INVISIBLE (1280 2932);
FORCEPROP 1 LAST PATH I68
J 0
(1400 2975);
DISPLAY 0.872340 (1400 2975);
PAINT AQUA (1400 2975);
DISPLAY INVISIBLE (1400 2975);
FORCEADD CAP..1
(1325 3175);
FORCEPROP 1 LAST PART_NUMBER G10601-001
J 0
(1375 3025);
DISPLAY 0.617021 (1375 3025);
PAINT BLUE (1375 3025);
FORCEPROP 1 LASTPIN (1325 3275) $PN 1
J 0
(1335 3255);
DISPLAY 0.617021 (1335 3255);
PAINT WHITE (1335 3255);
FORCEPROP 1 LAST VALUE 10UF
J 0
(1375 3225);
DISPLAY 0.617021 (1375 3225);
PAINT SKYBLUE (1375 3225);
FORCEPROP 1 LASTPIN (1325 3075) $PN 2
J 0
(1335 3055);
DISPLAY 0.617021 (1335 3055);
PAINT WHITE (1335 3055);
FORCEPROP 1 LAST LOCATION C6U18
J 0
(1375 3275);
DISPLAY 0.617021 (1375 3275);
PAINT AQUA (1375 3275);
FORCEPROP 1 LAST PACK_TYPE 0805
J 0
(1375 2975);
DISPLAY 0.617021 (1375 2975);
PAINT SKYBLUE (1375 2975);
FORCEPROP 1 LAST MATERIAL X7R
J 0
(1375 3075);
DISPLAY 0.617021 (1375 3075);
PAINT SKYBLUE (1375 3075);
FORCEPROP 1 LAST VOLTAGE 16V
J 0
(1375 3175);
DISPLAY 0.617021 (1375 3175);
PAINT SKYBLUE (1375 3175);
FORCEPROP 1 LAST TOLERANCE 10%
J 0
(1375 3125);
DISPLAY 0.617021 (1375 3125);
PAINT SKYBLUE (1375 3125);
FORCEPROP 0 LAST ROOM PVDDQ_ABC_PWR_VR
J 0
(1375 3325);
DISPLAY 1.021277 (1375 3325);
PAINT ORANGE (1375 3325);
DISPLAY INVISIBLE (1375 3325);
FORCEPROP 2 LAST CDS_LOCATION C6U18
J 0
(1375 3275);
DISPLAY 0.617021 (1375 3275);
PAINT AQUA (1375 3275);
DISPLAY INVISIBLE (1375 3275);
FORCEPROP 2 LAST $SEC 1
J 0
(1375 3375);
DISPLAY 0.914894 (1375 3375);
PAINT MONO (1375 3375);
DISPLAY INVISIBLE (1375 3375);
FORCEPROP 2 LAST CDS_SEC 1
J 0
(1375 3375);
DISPLAY 1.361702 (1375 3375);
PAINT ORANGE (1375 3375);
DISPLAY INVISIBLE (1375 3375);
FORCEPROP 2 LAST CDS_LIB mstr_discrete
J 0
(1325 3175);
PAINT ORANGE (1325 3175);
DISPLAY INVISIBLE (1325 3175);
FORCEPROP 1 LAST PATH I69
J 0
(1375 3325);
DISPLAY 0.978723 (1375 3325);
PAINT WHITE (1375 3325);
DISPLAY INVISIBLE (1375 3325);
FORCEADD GND..1
(1325 3550);
FORCEPROP 3 LASTPIN (1325 3600) SIG_NAME GND\g
J 0
(1335 3610);
DISPLAY 0.659574 (1335 3610);
PAINT MONO (1335 3610);
DISPLAY INVISIBLE (1335 3610);
FORCEPROP 1 LAST HDL_POWER GND
J 0
(1325 3700);
DISPLAY 1.170213 (1325 3700);
PAINT GREEN (1325 3700);
DISPLAY INVISIBLE (1325 3700);
FORCEPROP 1 LAST BODY_TYPE PLUMBING
J 0
(1280 3507);
DISPLAY 0.340426 (1280 3507);
PAINT GREEN (1280 3507);
DISPLAY INVISIBLE (1280 3507);
FORCEPROP 2 LAST CDS_LIB mstr_symbols
J 0
(1325 3550);
PAINT ORANGE (1325 3550);
DISPLAY INVISIBLE (1325 3550);
FORCEPROP 1 LAST SIZE 1B
J 0
(1400 3500);
DISPLAY 1.170213 (1400 3500);
PAINT AQUA (1400 3500);
DISPLAY INVISIBLE (1400 3500);
FORCEPROP 1 LAST VOLTAGE 0.0V
J 0
(1280 3507);
DISPLAY 0.340426 (1280 3507);
PAINT SKYBLUE (1280 3507);
DISPLAY INVISIBLE (1280 3507);
FORCEPROP 1 LAST PATH I70
J 0
(1400 3550);
DISPLAY 0.872340 (1400 3550);
PAINT AQUA (1400 3550);
DISPLAY INVISIBLE (1400 3550);
FORCEADD CAP..1
(1325 3750);
FORCEPROP 1 LAST TOLERANCE 10%
J 0
(1375 3700);
DISPLAY 0.617021 (1375 3700);
PAINT SKYBLUE (1375 3700);
FORCEPROP 1 LAST PART_NUMBER G10601-001
J 0
(1375 3600);
DISPLAY 0.617021 (1375 3600);
PAINT BLUE (1375 3600);
FORCEPROP 1 LAST PACK_TYPE 0805
J 0
(1375 3550);
DISPLAY 0.617021 (1375 3550);
PAINT SKYBLUE (1375 3550);
FORCEPROP 1 LAST VALUE 10UF
J 0
(1375 3800);
DISPLAY 0.617021 (1375 3800);
PAINT SKYBLUE (1375 3800);
FORCEPROP 1 LASTPIN (1325 3850) $PN 1
J 0
(1335 3830);
DISPLAY 0.617021 (1335 3830);
PAINT WHITE (1335 3830);
FORCEPROP 1 LASTPIN (1325 3650) $PN 2
J 0
(1335 3630);
DISPLAY 0.617021 (1335 3630);
PAINT WHITE (1335 3630);
FORCEPROP 1 LAST MATERIAL X7R
J 0
(1375 3650);
DISPLAY 0.617021 (1375 3650);
PAINT SKYBLUE (1375 3650);
FORCEPROP 1 LAST VOLTAGE 16V
J 0
(1375 3750);
DISPLAY 0.617021 (1375 3750);
PAINT SKYBLUE (1375 3750);
FORCEPROP 1 LAST LOCATION C6T2
J 0
(1375 3850);
DISPLAY 0.617021 (1375 3850);
PAINT AQUA (1375 3850);
FORCEPROP 0 LAST ROOM PVDDQ_ABC_PWR_VR
J 0
(1375 3900);
DISPLAY 1.021277 (1375 3900);
PAINT ORANGE (1375 3900);
DISPLAY INVISIBLE (1375 3900);
FORCEPROP 2 LAST CDS_LOCATION C6T2
J 0
(1375 3850);
DISPLAY 0.617021 (1375 3850);
PAINT AQUA (1375 3850);
DISPLAY INVISIBLE (1375 3850);
FORCEPROP 2 LAST $SEC 1
J 0
(1375 3950);
DISPLAY 0.914894 (1375 3950);
PAINT MONO (1375 3950);
DISPLAY INVISIBLE (1375 3950);
FORCEPROP 2 LAST CDS_SEC 1
J 0
(1375 3950);
DISPLAY 1.361702 (1375 3950);
PAINT ORANGE (1375 3950);
DISPLAY INVISIBLE (1375 3950);
FORCEPROP 2 LAST CDS_LIB mstr_discrete
J 0
(1325 3750);
PAINT ORANGE (1325 3750);
DISPLAY INVISIBLE (1325 3750);
FORCEPROP 1 LAST PATH I71
J 0
(1375 3900);
DISPLAY 0.978723 (1375 3900);
PAINT WHITE (1375 3900);
DISPLAY INVISIBLE (1375 3900);
FORCEADD CAP..1
(2175 1850);
FORCEPROP 1 LAST MATERIAL X7R
J 0
(2225 1750);
DISPLAY 0.617021 (2225 1750);
PAINT SKYBLUE (2225 1750);
FORCEPROP 1 LAST TOLERANCE 10%
J 0
(2225 1800);
DISPLAY 0.617021 (2225 1800);
PAINT SKYBLUE (2225 1800);
FORCEPROP 1 LAST PACK_TYPE 0805
J 0
(2225 1650);
DISPLAY 0.617021 (2225 1650);
PAINT SKYBLUE (2225 1650);
FORCEPROP 1 LASTPIN (2175 1750) $PN 2
J 0
(2185 1730);
DISPLAY 0.617021 (2185 1730);
PAINT WHITE (2185 1730);
FORCEPROP 1 LAST LOCATION C1B7
J 0
(2225 1950);
DISPLAY 0.617021 (2225 1950);
PAINT AQUA (2225 1950);
FORCEPROP 1 LAST VOLTAGE 16V
J 0
(2225 1850);
DISPLAY 0.617021 (2225 1850);
PAINT SKYBLUE (2225 1850);
FORCEPROP 1 LAST VALUE 10UF
J 0
(2225 1900);
DISPLAY 0.617021 (2225 1900);
PAINT SKYBLUE (2225 1900);
FORCEPROP 1 LASTPIN (2175 1950) $PN 1
J 0
(2185 1930);
DISPLAY 0.617021 (2185 1930);
PAINT WHITE (2185 1930);
FORCEPROP 1 LAST PART_NUMBER G10601-001
J 0
(2225 1700);
DISPLAY 0.617021 (2225 1700);
PAINT BLUE (2225 1700);
FORCEPROP 0 LAST ROOM PVDDQ_KLM_PWR_VR
J 0
(2225 2000);
DISPLAY 1.021277 (2225 2000);
PAINT ORANGE (2225 2000);
DISPLAY INVISIBLE (2225 2000);
FORCEPROP 2 LAST CDS_LOCATION C1B7
J 0
(2225 1950);
DISPLAY 0.617021 (2225 1950);
PAINT AQUA (2225 1950);
DISPLAY INVISIBLE (2225 1950);
FORCEPROP 2 LAST $SEC 1
J 0
(2225 2050);
DISPLAY 0.914894 (2225 2050);
PAINT MONO (2225 2050);
DISPLAY INVISIBLE (2225 2050);
FORCEPROP 2 LAST CDS_SEC 1
J 0
(2225 2050);
DISPLAY 1.361702 (2225 2050);
PAINT ORANGE (2225 2050);
DISPLAY INVISIBLE (2225 2050);
FORCEPROP 2 LAST CDS_LIB mstr_discrete
J 0
(2175 1850);
PAINT ORANGE (2175 1850);
DISPLAY INVISIBLE (2175 1850);
FORCEPROP 1 LAST PATH I72
J 0
(2225 2000);
DISPLAY 0.978723 (2225 2000);
PAINT WHITE (2225 2000);
DISPLAY INVISIBLE (2225 2000);
FORCEADD P12V_NVDIMM_KLM..1
(2175 2025);
FORCEPROP 3 LASTPIN (2175 1975) SIG_NAME P12V_NVDIMM_KLM\g
J 0
(2185 1985);
DISPLAY 0.659574 (2185 1985);
PAINT MONO (2185 1985);
DISPLAY INVISIBLE (2185 1985);
FORCEPROP 1 LAST HDL_POWER P12V_NVDIMM_KLM
J 1
(2175 2075);
DISPLAY 0.872340 (2175 2075);
PAINT GREEN (2175 2075);
DISPLAY INVISIBLE (2175 2075);
FORCEPROP 1 LAST BODY_TYPE PLUMBING
J 0
(2130 1982);
DISPLAY 0.340426 (2130 1982);
PAINT GREEN (2130 1982);
DISPLAY INVISIBLE (2130 1982);
FORCEPROP 2 LAST CDS_LIB mstr_symbols
J 0
(2175 2025);
PAINT ORANGE (2175 2025);
DISPLAY INVISIBLE (2175 2025);
FORCEPROP 1 LAST VOLTAGE 12.0
J 0
(2130 1982);
DISPLAY 0.340426 (2130 1982);
PAINT SKYBLUE (2130 1982);
DISPLAY INVISIBLE (2130 1982);
FORCEPROP 1 LAST PATH I73
J 0
(2225 2050);
DISPLAY 0.872340 (2225 2050);
PAINT AQUA (2225 2050);
DISPLAY INVISIBLE (2225 2050);
FORCEADD GND..1
(2175 2300);
FORCEPROP 3 LASTPIN (2175 2350) SIG_NAME GND\g
J 0
(2185 2360);
DISPLAY 0.659574 (2185 2360);
PAINT MONO (2185 2360);
DISPLAY INVISIBLE (2185 2360);
FORCEPROP 1 LAST HDL_POWER GND
J 0
(2175 2450);
DISPLAY 1.170213 (2175 2450);
PAINT GREEN (2175 2450);
DISPLAY INVISIBLE (2175 2450);
FORCEPROP 1 LAST BODY_TYPE PLUMBING
J 0
(2130 2257);
DISPLAY 0.340426 (2130 2257);
PAINT GREEN (2130 2257);
DISPLAY INVISIBLE (2130 2257);
FORCEPROP 1 LAST SIZE 1B
J 0
(2250 2250);
DISPLAY 1.170213 (2250 2250);
PAINT AQUA (2250 2250);
DISPLAY INVISIBLE (2250 2250);
FORCEPROP 2 LAST CDS_LIB mstr_symbols
J 0
(2175 2300);
PAINT ORANGE (2175 2300);
DISPLAY INVISIBLE (2175 2300);
FORCEPROP 1 LAST VOLTAGE 0.0V
J 0
(2130 2257);
DISPLAY 0.340426 (2130 2257);
PAINT SKYBLUE (2130 2257);
DISPLAY INVISIBLE (2130 2257);
FORCEPROP 1 LAST PATH I74
J 0
(2250 2300);
DISPLAY 0.872340 (2250 2300);
PAINT AQUA (2250 2300);
DISPLAY INVISIBLE (2250 2300);
FORCEADD CAP..1
(2175 2500);
FORCEPROP 1 LAST TOLERANCE 10%
J 0
(2225 2450);
DISPLAY 0.617021 (2225 2450);
PAINT SKYBLUE (2225 2450);
FORCEPROP 1 LASTPIN (2175 2400) $PN 2
J 0
(2185 2380);
DISPLAY 0.617021 (2185 2380);
PAINT WHITE (2185 2380);
FORCEPROP 1 LAST PACK_TYPE 0805
J 0
(2225 2300);
DISPLAY 0.617021 (2225 2300);
PAINT SKYBLUE (2225 2300);
FORCEPROP 1 LAST PART_NUMBER G10601-001
J 0
(2225 2350);
DISPLAY 0.617021 (2225 2350);
PAINT BLUE (2225 2350);
FORCEPROP 1 LAST LOCATION C1A16
J 0
(2225 2600);
DISPLAY 0.617021 (2225 2600);
PAINT AQUA (2225 2600);
FORCEPROP 1 LAST VALUE 10UF
J 0
(2225 2550);
DISPLAY 0.617021 (2225 2550);
PAINT SKYBLUE (2225 2550);
FORCEPROP 1 LAST VOLTAGE 16V
J 0
(2225 2500);
DISPLAY 0.617021 (2225 2500);
PAINT SKYBLUE (2225 2500);
FORCEPROP 1 LAST MATERIAL X7R
J 0
(2225 2400);
DISPLAY 0.617021 (2225 2400);
PAINT SKYBLUE (2225 2400);
FORCEPROP 1 LASTPIN (2175 2600) $PN 1
J 0
(2185 2580);
DISPLAY 0.617021 (2185 2580);
PAINT WHITE (2185 2580);
FORCEPROP 0 LAST ROOM PVDDQ_KLM_PWR_VR
J 0
(2225 2650);
DISPLAY 1.021277 (2225 2650);
PAINT ORANGE (2225 2650);
DISPLAY INVISIBLE (2225 2650);
FORCEPROP 2 LAST CDS_LOCATION C1A16
J 0
(2225 2600);
DISPLAY 0.617021 (2225 2600);
PAINT AQUA (2225 2600);
DISPLAY INVISIBLE (2225 2600);
FORCEPROP 2 LAST $SEC 1
J 0
(2225 2700);
DISPLAY 0.914894 (2225 2700);
PAINT MONO (2225 2700);
DISPLAY INVISIBLE (2225 2700);
FORCEPROP 2 LAST CDS_SEC 1
J 0
(2225 2700);
DISPLAY 1.361702 (2225 2700);
PAINT ORANGE (2225 2700);
DISPLAY INVISIBLE (2225 2700);
FORCEPROP 2 LAST CDS_LIB mstr_discrete
J 0
(2175 2500);
PAINT ORANGE (2175 2500);
DISPLAY INVISIBLE (2175 2500);
FORCEPROP 1 LAST PATH I75
J 0
(2225 2650);
DISPLAY 0.978723 (2225 2650);
PAINT WHITE (2225 2650);
DISPLAY INVISIBLE (2225 2650);
FORCEADD P12V_NVDIMM_KLM..1
(2175 2675);
FORCEPROP 3 LASTPIN (2175 2625) SIG_NAME P12V_NVDIMM_KLM\g
J 0
(2185 2635);
DISPLAY 0.659574 (2185 2635);
PAINT MONO (2185 2635);
DISPLAY INVISIBLE (2185 2635);
FORCEPROP 1 LAST HDL_POWER P12V_NVDIMM_KLM
J 1
(2175 2725);
DISPLAY 0.872340 (2175 2725);
PAINT GREEN (2175 2725);
DISPLAY INVISIBLE (2175 2725);
FORCEPROP 1 LAST BODY_TYPE PLUMBING
J 0
(2130 2632);
DISPLAY 0.340426 (2130 2632);
PAINT GREEN (2130 2632);
DISPLAY INVISIBLE (2130 2632);
FORCEPROP 2 LAST CDS_LIB mstr_symbols
J 0
(2175 2675);
PAINT ORANGE (2175 2675);
DISPLAY INVISIBLE (2175 2675);
FORCEPROP 1 LAST VOLTAGE 12.0
J 0
(2130 2632);
DISPLAY 0.340426 (2130 2632);
PAINT SKYBLUE (2130 2632);
DISPLAY INVISIBLE (2130 2632);
FORCEPROP 1 LAST PATH I76
J 0
(2225 2700);
DISPLAY 0.872340 (2225 2700);
PAINT AQUA (2225 2700);
DISPLAY INVISIBLE (2225 2700);
FORCEADD GND..1
(2175 2975);
FORCEPROP 3 LASTPIN (2175 3025) SIG_NAME GND\g
J 0
(2185 3035);
DISPLAY 0.659574 (2185 3035);
PAINT MONO (2185 3035);
DISPLAY INVISIBLE (2185 3035);
FORCEPROP 1 LAST HDL_POWER GND
J 0
(2175 3125);
DISPLAY 1.170213 (2175 3125);
PAINT GREEN (2175 3125);
DISPLAY INVISIBLE (2175 3125);
FORCEPROP 1 LAST BODY_TYPE PLUMBING
J 0
(2130 2932);
DISPLAY 0.340426 (2130 2932);
PAINT GREEN (2130 2932);
DISPLAY INVISIBLE (2130 2932);
FORCEPROP 1 LAST SIZE 1B
J 0
(2250 2925);
DISPLAY 1.170213 (2250 2925);
PAINT AQUA (2250 2925);
DISPLAY INVISIBLE (2250 2925);
FORCEPROP 2 LAST CDS_LIB mstr_symbols
J 0
(2175 2975);
PAINT ORANGE (2175 2975);
DISPLAY INVISIBLE (2175 2975);
FORCEPROP 1 LAST VOLTAGE 0.0V
J 0
(2130 2932);
DISPLAY 0.340426 (2130 2932);
PAINT SKYBLUE (2130 2932);
DISPLAY INVISIBLE (2130 2932);
FORCEPROP 1 LAST PATH I77
J 0
(2250 2975);
DISPLAY 0.872340 (2250 2975);
PAINT AQUA (2250 2975);
DISPLAY INVISIBLE (2250 2975);
FORCEADD CAP..1
(2175 3175);
FORCEPROP 1 LAST TOLERANCE 10%
J 0
(2225 3125);
DISPLAY 0.617021 (2225 3125);
PAINT SKYBLUE (2225 3125);
FORCEPROP 1 LAST PART_NUMBER G10601-001
J 0
(2225 3025);
DISPLAY 0.617021 (2225 3025);
PAINT BLUE (2225 3025);
FORCEPROP 1 LAST PACK_TYPE 0805
J 0
(2225 2975);
DISPLAY 0.617021 (2225 2975);
PAINT SKYBLUE (2225 2975);
FORCEPROP 1 LASTPIN (2175 3075) $PN 2
J 0
(2185 3055);
DISPLAY 0.617021 (2185 3055);
PAINT WHITE (2185 3055);
FORCEPROP 1 LASTPIN (2175 3275) $PN 1
J 0
(2185 3255);
DISPLAY 0.617021 (2185 3255);
PAINT WHITE (2185 3255);
FORCEPROP 1 LAST VOLTAGE 16V
J 0
(2225 3175);
DISPLAY 0.617021 (2225 3175);
PAINT SKYBLUE (2225 3175);
FORCEPROP 1 LAST VALUE 10UF
J 0
(2225 3225);
DISPLAY 0.617021 (2225 3225);
PAINT SKYBLUE (2225 3225);
FORCEPROP 1 LAST LOCATION C4B11
J 0
(2225 3275);
DISPLAY 0.617021 (2225 3275);
PAINT AQUA (2225 3275);
FORCEPROP 1 LAST MATERIAL X7R
J 0
(2225 3075);
DISPLAY 0.617021 (2225 3075);
PAINT SKYBLUE (2225 3075);
FORCEPROP 0 LAST ROOM PVDDQ_DEF_PWR_VR
J 0
(2225 3325);
DISPLAY 1.021277 (2225 3325);
PAINT ORANGE (2225 3325);
DISPLAY INVISIBLE (2225 3325);
FORCEPROP 2 LAST CDS_LOCATION C4B11
J 0
(2225 3275);
DISPLAY 0.617021 (2225 3275);
PAINT AQUA (2225 3275);
DISPLAY INVISIBLE (2225 3275);
FORCEPROP 2 LAST $SEC 1
J 0
(2225 3375);
DISPLAY 0.914894 (2225 3375);
PAINT MONO (2225 3375);
DISPLAY INVISIBLE (2225 3375);
FORCEPROP 2 LAST CDS_SEC 1
J 0
(2225 3375);
DISPLAY 1.361702 (2225 3375);
PAINT ORANGE (2225 3375);
DISPLAY INVISIBLE (2225 3375);
FORCEPROP 2 LAST CDS_LIB mstr_discrete
J 0
(2175 3175);
PAINT ORANGE (2175 3175);
DISPLAY INVISIBLE (2175 3175);
FORCEPROP 1 LAST PATH I78
J 0
(2225 3325);
DISPLAY 0.978723 (2225 3325);
PAINT WHITE (2225 3325);
DISPLAY INVISIBLE (2225 3325);
FORCEADD P12V_NVDIMM_DEF..1
(2175 3350);
FORCEPROP 3 LASTPIN (2175 3300) SIG_NAME P12V_NVDIMM_DEF\g
J 0
(2185 3310);
DISPLAY 0.659574 (2185 3310);
PAINT MONO (2185 3310);
DISPLAY INVISIBLE (2185 3310);
FORCEPROP 1 LAST HDL_POWER P12V_NVDIMM_DEF
J 1
(2175 3400);
DISPLAY 0.872340 (2175 3400);
PAINT GREEN (2175 3400);
DISPLAY INVISIBLE (2175 3400);
FORCEPROP 1 LAST BODY_TYPE PLUMBING
J 0
(2130 3307);
DISPLAY 0.340426 (2130 3307);
PAINT GREEN (2130 3307);
DISPLAY INVISIBLE (2130 3307);
FORCEPROP 2 LAST CDS_LIB mstr_symbols
J 0
(2175 3350);
PAINT ORANGE (2175 3350);
DISPLAY INVISIBLE (2175 3350);
FORCEPROP 1 LAST VOLTAGE 12.0
J 0
(2130 3307);
DISPLAY 0.340426 (2130 3307);
PAINT SKYBLUE (2130 3307);
DISPLAY INVISIBLE (2130 3307);
FORCEPROP 1 LAST PATH I79
J 0
(2225 3375);
DISPLAY 0.872340 (2225 3375);
PAINT AQUA (2225 3375);
DISPLAY INVISIBLE (2225 3375);
FORCEADD CAP..1
R 1
(-4275 3550);
FORCEPROP 1 LAST TOLERANCE 5%
J 0
(-4425 3325);
DISPLAY 0.617021 (-4425 3325);
PAINT SKYBLUE (-4425 3325);
FORCEPROP 1 LASTPIN (-4175 3550) $PN 2
J 0
(-4155 3560);
DISPLAY 0.617021 (-4155 3560);
PAINT MONO (-4155 3560);
FORCEPROP 1 LAST PART_NUMBER A36095-025
J 0
(-4250 3425);
DISPLAY 0.617021 (-4250 3425);
PAINT BLUE (-4250 3425);
FORCEPROP 1 LAST MATERIAL COG
J 0
(-4250 3475);
DISPLAY 0.617021 (-4250 3475);
PAINT SKYBLUE (-4250 3475);
FORCEPROP 1 LAST PACK_TYPE 0402LF
J 0
(-4250 3375);
DISPLAY 0.617021 (-4250 3375);
PAINT SKYBLUE (-4250 3375);
FORCEPROP 1 LAST VOLTAGE 50V
J 0
(-4425 3375);
DISPLAY 0.617021 (-4425 3375);
PAINT SKYBLUE (-4425 3375);
FORCEPROP 1 LAST VALUE 47.0PF
J 0
(-4425 3425);
DISPLAY 0.617021 (-4425 3425);
PAINT SKYBLUE (-4425 3425);
FORCEPROP 1 LAST LOCATION C12W1
J 0
(-4425 3475);
DISPLAY 0.617021 (-4425 3475);
PAINT AQUA (-4425 3475);
FORCEPROP 1 LASTPIN (-4375 3550) $PN 1
J 0
(-4405 3560);
DISPLAY 0.617021 (-4405 3560);
PAINT MONO (-4405 3560);
FORCEPROP 2 LAST BOM_COST SM_HM
R 1
J 0
(-4475 3600);
DISPLAY 1.021277 (-4475 3600);
PAINT ORANGE (-4475 3600);
DISPLAY INVISIBLE (-4475 3600);
FORCEPROP 2 LAST CDS_LIB mstr_discrete
R 1
J 0
(-4275 3550);
DISPLAY 1.361702 (-4275 3550);
PAINT ORANGE (-4275 3550);
DISPLAY INVISIBLE (-4275 3550);
FORCEPROP 2 LAST SEC_TYPE 0402LF
R 1
J 0
(-4475 3600);
PAINT MONO (-4475 3600);
DISPLAY INVISIBLE (-4475 3600);
FORCEPROP 2 LAST SEC 1
R 1
J 0
(-4475 3600);
DISPLAY 0.936170 (-4475 3600);
PAINT MONO (-4475 3600);
DISPLAY INVISIBLE (-4475 3600);
FORCEPROP 2 LAST ROOM BMC_VOLT_MONITOR
R 1
J 0
(-4425 3600);
DISPLAY 1.021277 (-4425 3600);
PAINT ORANGE (-4425 3600);
DISPLAY INVISIBLE (-4425 3600);
FORCEPROP 2 LAST CDS_LOCATION C12W1
R 1
J 0
(-4375 3600);
DISPLAY 0.617021 (-4375 3600);
PAINT AQUA (-4375 3600);
DISPLAY INVISIBLE (-4375 3600);
FORCEPROP 0 LAST CDS_SEC 1
R 1
J 0
(-4400 3500);
PAINT MONO (-4400 3500);
DISPLAY INVISIBLE (-4400 3500);
FORCEPROP 1 LAST PATH I8
R 1
J 0
(-4425 3600);
DISPLAY 0.978723 (-4425 3600);
PAINT WHITE (-4425 3600);
DISPLAY INVISIBLE (-4425 3600);
FORCEADD GND..1
(2175 3550);
FORCEPROP 3 LASTPIN (2175 3600) SIG_NAME GND\g
J 0
(2185 3610);
DISPLAY 0.659574 (2185 3610);
PAINT MONO (2185 3610);
DISPLAY INVISIBLE (2185 3610);
FORCEPROP 1 LAST HDL_POWER GND
J 0
(2175 3700);
DISPLAY 1.170213 (2175 3700);
PAINT GREEN (2175 3700);
DISPLAY INVISIBLE (2175 3700);
FORCEPROP 1 LAST BODY_TYPE PLUMBING
J 0
(2130 3507);
DISPLAY 0.340426 (2130 3507);
PAINT GREEN (2130 3507);
DISPLAY INVISIBLE (2130 3507);
FORCEPROP 1 LAST SIZE 1B
J 0
(2250 3500);
DISPLAY 1.170213 (2250 3500);
PAINT AQUA (2250 3500);
DISPLAY INVISIBLE (2250 3500);
FORCEPROP 2 LAST CDS_LIB mstr_symbols
J 0
(2175 3550);
PAINT ORANGE (2175 3550);
DISPLAY INVISIBLE (2175 3550);
FORCEPROP 1 LAST VOLTAGE 0.0V
J 0
(2130 3507);
DISPLAY 0.340426 (2130 3507);
PAINT SKYBLUE (2130 3507);
DISPLAY INVISIBLE (2130 3507);
FORCEPROP 1 LAST PATH I80
J 0
(2250 3550);
DISPLAY 0.872340 (2250 3550);
PAINT AQUA (2250 3550);
DISPLAY INVISIBLE (2250 3550);
FORCEADD CAP..1
(2175 3750);
FORCEPROP 1 LASTPIN (2175 3850) $PN 1
J 0
(2185 3830);
DISPLAY 0.617021 (2185 3830);
PAINT WHITE (2185 3830);
FORCEPROP 1 LASTPIN (2175 3650) $PN 2
J 0
(2185 3630);
DISPLAY 0.617021 (2185 3630);
PAINT WHITE (2185 3630);
FORCEPROP 1 LAST MATERIAL X7R
J 0
(2225 3650);
DISPLAY 0.617021 (2225 3650);
PAINT SKYBLUE (2225 3650);
FORCEPROP 1 LAST VOLTAGE 16V
J 0
(2225 3750);
DISPLAY 0.617021 (2225 3750);
PAINT SKYBLUE (2225 3750);
FORCEPROP 1 LAST TOLERANCE 10%
J 0
(2225 3700);
DISPLAY 0.617021 (2225 3700);
PAINT SKYBLUE (2225 3700);
FORCEPROP 1 LAST PART_NUMBER G10601-001
J 0
(2225 3600);
DISPLAY 0.617021 (2225 3600);
PAINT BLUE (2225 3600);
FORCEPROP 1 LAST PACK_TYPE 0805
J 0
(2225 3550);
DISPLAY 0.617021 (2225 3550);
PAINT SKYBLUE (2225 3550);
FORCEPROP 1 LAST VALUE 10UF
J 0
(2225 3800);
DISPLAY 0.617021 (2225 3800);
PAINT SKYBLUE (2225 3800);
FORCEPROP 1 LAST LOCATION C4A4
J 0
(2225 3850);
DISPLAY 0.617021 (2225 3850);
PAINT AQUA (2225 3850);
FORCEPROP 0 LAST ROOM PVDDQ_DEF_PWR_VR
J 0
(2225 3900);
DISPLAY 1.021277 (2225 3900);
PAINT ORANGE (2225 3900);
DISPLAY INVISIBLE (2225 3900);
FORCEPROP 2 LAST CDS_LOCATION C4A4
J 0
(2225 3850);
DISPLAY 0.617021 (2225 3850);
PAINT AQUA (2225 3850);
DISPLAY INVISIBLE (2225 3850);
FORCEPROP 2 LAST $SEC 1
J 0
(2225 3950);
DISPLAY 0.914894 (2225 3950);
PAINT MONO (2225 3950);
DISPLAY INVISIBLE (2225 3950);
FORCEPROP 2 LAST CDS_SEC 1
J 0
(2225 3950);
DISPLAY 1.361702 (2225 3950);
PAINT ORANGE (2225 3950);
DISPLAY INVISIBLE (2225 3950);
FORCEPROP 2 LAST CDS_LIB mstr_discrete
J 0
(2175 3750);
PAINT ORANGE (2175 3750);
DISPLAY INVISIBLE (2175 3750);
FORCEPROP 1 LAST PATH I81
J 0
(2225 3900);
DISPLAY 0.978723 (2225 3900);
PAINT WHITE (2225 3900);
DISPLAY INVISIBLE (2225 3900);
FORCEADD P12V_NVDIMM_ABC..1
(1325 3925);
FORCEPROP 3 LASTPIN (1325 3875) SIG_NAME P12V_NVDIMM_ABC\g
J 0
(1335 3885);
DISPLAY 0.659574 (1335 3885);
PAINT MONO (1335 3885);
DISPLAY INVISIBLE (1335 3885);
FORCEPROP 1 LAST HDL_POWER P12V_NVDIMM_ABC
J 1
(1325 3950);
DISPLAY 0.872340 (1325 3950);
PAINT GREEN (1325 3950);
DISPLAY INVISIBLE (1325 3950);
FORCEPROP 1 LAST BODY_TYPE PLUMBING
J 0
(1280 3882);
DISPLAY 0.340426 (1280 3882);
PAINT GREEN (1280 3882);
DISPLAY INVISIBLE (1280 3882);
FORCEPROP 2 LAST CDS_LIB mstr_symbols
J 0
(1325 3925);
PAINT ORANGE (1325 3925);
DISPLAY INVISIBLE (1325 3925);
FORCEPROP 1 LAST VOLTAGE 12.0
J 0
(1280 3882);
DISPLAY 0.340426 (1280 3882);
PAINT SKYBLUE (1280 3882);
DISPLAY INVISIBLE (1280 3882);
FORCEPROP 1 LAST PATH I82
J 0
(1375 3950);
DISPLAY 0.872340 (1375 3950);
PAINT AQUA (1375 3950);
DISPLAY INVISIBLE (1375 3950);
FORCEADD GND..1
(1325 4200);
FORCEPROP 3 LASTPIN (1325 4250) SIG_NAME GND\g
J 0
(1335 4260);
DISPLAY 0.659574 (1335 4260);
PAINT MONO (1335 4260);
DISPLAY INVISIBLE (1335 4260);
FORCEPROP 1 LAST HDL_POWER GND
J 0
(1325 4350);
DISPLAY 1.170213 (1325 4350);
PAINT GREEN (1325 4350);
DISPLAY INVISIBLE (1325 4350);
FORCEPROP 1 LAST BODY_TYPE PLUMBING
J 0
(1280 4157);
DISPLAY 0.340426 (1280 4157);
PAINT GREEN (1280 4157);
DISPLAY INVISIBLE (1280 4157);
FORCEPROP 2 LAST CDS_LIB mstr_symbols
J 0
(1325 4200);
PAINT ORANGE (1325 4200);
DISPLAY INVISIBLE (1325 4200);
FORCEPROP 1 LAST SIZE 1B
J 0
(1400 4150);
DISPLAY 1.170213 (1400 4150);
PAINT AQUA (1400 4150);
DISPLAY INVISIBLE (1400 4150);
FORCEPROP 1 LAST VOLTAGE 0.0V
J 0
(1280 4157);
DISPLAY 0.340426 (1280 4157);
PAINT SKYBLUE (1280 4157);
DISPLAY INVISIBLE (1280 4157);
FORCEPROP 1 LAST PATH I83
J 0
(1400 4200);
DISPLAY 0.872340 (1400 4200);
PAINT AQUA (1400 4200);
DISPLAY INVISIBLE (1400 4200);
FORCEADD CAP..1
(1325 4400);
FORCEPROP 1 LAST PART_NUMBER G10601-001
J 0
(1375 4250);
DISPLAY 0.617021 (1375 4250);
PAINT BLUE (1375 4250);
FORCEPROP 1 LAST MATERIAL X7R
J 0
(1375 4300);
DISPLAY 0.617021 (1375 4300);
PAINT SKYBLUE (1375 4300);
FORCEPROP 1 LAST LOCATION C6U10
J 0
(1375 4500);
DISPLAY 0.617021 (1375 4500);
PAINT AQUA (1375 4500);
FORCEPROP 1 LAST VALUE 10UF
J 0
(1375 4450);
DISPLAY 0.617021 (1375 4450);
PAINT SKYBLUE (1375 4450);
FORCEPROP 1 LASTPIN (1325 4500) $PN 1
J 0
(1335 4480);
DISPLAY 0.617021 (1335 4480);
PAINT WHITE (1335 4480);
FORCEPROP 1 LASTPIN (1325 4300) $PN 2
J 0
(1335 4280);
DISPLAY 0.617021 (1335 4280);
PAINT WHITE (1335 4280);
FORCEPROP 1 LAST VOLTAGE 16V
J 0
(1375 4400);
DISPLAY 0.617021 (1375 4400);
PAINT SKYBLUE (1375 4400);
FORCEPROP 1 LAST PACK_TYPE 0805
J 0
(1375 4200);
DISPLAY 0.617021 (1375 4200);
PAINT SKYBLUE (1375 4200);
FORCEPROP 1 LAST TOLERANCE 10%
J 0
(1375 4350);
DISPLAY 0.617021 (1375 4350);
PAINT SKYBLUE (1375 4350);
FORCEPROP 0 LAST ROOM PVDDQ_ABC_PWR_VR
J 0
(1375 4550);
DISPLAY 1.021277 (1375 4550);
PAINT ORANGE (1375 4550);
DISPLAY INVISIBLE (1375 4550);
FORCEPROP 2 LAST CDS_LOCATION C6U10
J 0
(1375 4500);
DISPLAY 0.617021 (1375 4500);
PAINT AQUA (1375 4500);
DISPLAY INVISIBLE (1375 4500);
FORCEPROP 2 LAST $SEC 1
J 0
(1375 4600);
DISPLAY 0.914894 (1375 4600);
PAINT MONO (1375 4600);
DISPLAY INVISIBLE (1375 4600);
FORCEPROP 2 LAST CDS_SEC 1
J 0
(1375 4600);
DISPLAY 1.361702 (1375 4600);
PAINT ORANGE (1375 4600);
DISPLAY INVISIBLE (1375 4600);
FORCEPROP 2 LAST CDS_LIB mstr_discrete
J 0
(1325 4400);
PAINT ORANGE (1325 4400);
DISPLAY INVISIBLE (1325 4400);
FORCEPROP 1 LAST PATH I84
J 0
(1375 4550);
DISPLAY 0.978723 (1375 4550);
PAINT WHITE (1375 4550);
DISPLAY INVISIBLE (1375 4550);
FORCEADD P12V_NVDIMM_ABC..1
(1325 4575);
FORCEPROP 3 LASTPIN (1325 4525) SIG_NAME P12V_NVDIMM_ABC\g
J 0
(1335 4535);
DISPLAY 0.659574 (1335 4535);
PAINT MONO (1335 4535);
DISPLAY INVISIBLE (1335 4535);
FORCEPROP 1 LAST HDL_POWER P12V_NVDIMM_ABC
J 1
(1325 4600);
DISPLAY 0.872340 (1325 4600);
PAINT GREEN (1325 4600);
DISPLAY INVISIBLE (1325 4600);
FORCEPROP 1 LAST BODY_TYPE PLUMBING
J 0
(1280 4532);
DISPLAY 0.340426 (1280 4532);
PAINT GREEN (1280 4532);
DISPLAY INVISIBLE (1280 4532);
FORCEPROP 2 LAST CDS_LIB mstr_symbols
J 0
(1325 4575);
PAINT ORANGE (1325 4575);
DISPLAY INVISIBLE (1325 4575);
FORCEPROP 1 LAST VOLTAGE 12.0
J 0
(1280 4532);
DISPLAY 0.340426 (1280 4532);
PAINT SKYBLUE (1280 4532);
DISPLAY INVISIBLE (1280 4532);
FORCEPROP 1 LAST PATH I85
J 0
(1375 4600);
DISPLAY 0.872340 (1375 4600);
PAINT AQUA (1375 4600);
DISPLAY INVISIBLE (1375 4600);
FORCEADD P12V_NVDIMM_DEF..1
(2175 3925);
FORCEPROP 3 LASTPIN (2175 3875) SIG_NAME P12V_NVDIMM_DEF\g
J 0
(2185 3885);
DISPLAY 0.659574 (2185 3885);
PAINT MONO (2185 3885);
DISPLAY INVISIBLE (2185 3885);
FORCEPROP 1 LAST HDL_POWER P12V_NVDIMM_DEF
J 1
(2175 3975);
DISPLAY 0.872340 (2175 3975);
PAINT GREEN (2175 3975);
DISPLAY INVISIBLE (2175 3975);
FORCEPROP 1 LAST BODY_TYPE PLUMBING
J 0
(2130 3882);
DISPLAY 0.340426 (2130 3882);
PAINT GREEN (2130 3882);
DISPLAY INVISIBLE (2130 3882);
FORCEPROP 2 LAST CDS_LIB mstr_symbols
J 0
(2175 3925);
PAINT ORANGE (2175 3925);
DISPLAY INVISIBLE (2175 3925);
FORCEPROP 1 LAST VOLTAGE 12.0
J 0
(2130 3882);
DISPLAY 0.340426 (2130 3882);
PAINT SKYBLUE (2130 3882);
DISPLAY INVISIBLE (2130 3882);
FORCEPROP 1 LAST PATH I86
J 0
(2225 3950);
DISPLAY 0.872340 (2225 3950);
PAINT AQUA (2225 3950);
DISPLAY INVISIBLE (2225 3950);
FORCEADD GND..1
(2175 4200);
FORCEPROP 3 LASTPIN (2175 4250) SIG_NAME GND\g
J 0
(2185 4260);
DISPLAY 0.659574 (2185 4260);
PAINT MONO (2185 4260);
DISPLAY INVISIBLE (2185 4260);
FORCEPROP 1 LAST HDL_POWER GND
J 0
(2175 4350);
DISPLAY 1.170213 (2175 4350);
PAINT GREEN (2175 4350);
DISPLAY INVISIBLE (2175 4350);
FORCEPROP 1 LAST BODY_TYPE PLUMBING
J 0
(2130 4157);
DISPLAY 0.340426 (2130 4157);
PAINT GREEN (2130 4157);
DISPLAY INVISIBLE (2130 4157);
FORCEPROP 2 LAST CDS_LIB mstr_symbols
J 0
(2175 4200);
PAINT ORANGE (2175 4200);
DISPLAY INVISIBLE (2175 4200);
FORCEPROP 1 LAST SIZE 1B
J 0
(2250 4150);
DISPLAY 1.170213 (2250 4150);
PAINT AQUA (2250 4150);
DISPLAY INVISIBLE (2250 4150);
FORCEPROP 1 LAST VOLTAGE 0.0V
J 0
(2130 4157);
DISPLAY 0.340426 (2130 4157);
PAINT SKYBLUE (2130 4157);
DISPLAY INVISIBLE (2130 4157);
FORCEPROP 1 LAST PATH I87
J 0
(2250 4200);
DISPLAY 0.872340 (2250 4200);
PAINT AQUA (2250 4200);
DISPLAY INVISIBLE (2250 4200);
FORCEADD CAP..1
(2175 4400);
FORCEPROP 1 LASTPIN (2175 4500) $PN 1
J 0
(2185 4480);
DISPLAY 0.617021 (2185 4480);
PAINT WHITE (2185 4480);
FORCEPROP 1 LASTPIN (2175 4300) $PN 2
J 0
(2185 4280);
DISPLAY 0.617021 (2185 4280);
PAINT WHITE (2185 4280);
FORCEPROP 1 LAST MATERIAL X7R
J 0
(2225 4300);
DISPLAY 0.617021 (2225 4300);
PAINT SKYBLUE (2225 4300);
FORCEPROP 1 LAST VOLTAGE 16V
J 0
(2225 4400);
DISPLAY 0.617021 (2225 4400);
PAINT SKYBLUE (2225 4400);
FORCEPROP 1 LAST TOLERANCE 10%
J 0
(2225 4350);
DISPLAY 0.617021 (2225 4350);
PAINT SKYBLUE (2225 4350);
FORCEPROP 1 LAST VALUE 10UF
J 0
(2225 4450);
DISPLAY 0.617021 (2225 4450);
PAINT SKYBLUE (2225 4450);
FORCEPROP 1 LAST LOCATION C4A17
J 0
(2225 4500);
DISPLAY 0.617021 (2225 4500);
PAINT AQUA (2225 4500);
FORCEPROP 1 LAST PART_NUMBER G10601-001
J 0
(2225 4250);
DISPLAY 0.617021 (2225 4250);
PAINT BLUE (2225 4250);
FORCEPROP 1 LAST PACK_TYPE 0805
J 0
(2225 4200);
DISPLAY 0.617021 (2225 4200);
PAINT SKYBLUE (2225 4200);
FORCEPROP 0 LAST ROOM PVDDQ_DEF_PWR_VR
J 0
(2225 4550);
DISPLAY 1.021277 (2225 4550);
PAINT ORANGE (2225 4550);
DISPLAY INVISIBLE (2225 4550);
FORCEPROP 2 LAST CDS_LOCATION C4A17
J 0
(2225 4500);
DISPLAY 0.617021 (2225 4500);
PAINT AQUA (2225 4500);
DISPLAY INVISIBLE (2225 4500);
FORCEPROP 2 LAST $SEC 1
J 0
(2225 4600);
DISPLAY 0.914894 (2225 4600);
PAINT MONO (2225 4600);
DISPLAY INVISIBLE (2225 4600);
FORCEPROP 2 LAST CDS_SEC 1
J 0
(2225 4600);
DISPLAY 1.361702 (2225 4600);
PAINT ORANGE (2225 4600);
DISPLAY INVISIBLE (2225 4600);
FORCEPROP 2 LAST CDS_LIB mstr_discrete
J 0
(2175 4400);
PAINT ORANGE (2175 4400);
DISPLAY INVISIBLE (2175 4400);
FORCEPROP 1 LAST PATH I88
J 0
(2225 4550);
DISPLAY 0.978723 (2225 4550);
PAINT WHITE (2225 4550);
DISPLAY INVISIBLE (2225 4550);
FORCEADD P12V_NVDIMM_DEF..1
(2175 4575);
FORCEPROP 3 LASTPIN (2175 4525) SIG_NAME P12V_NVDIMM_DEF\g
J 0
(2185 4535);
DISPLAY 0.659574 (2185 4535);
PAINT MONO (2185 4535);
DISPLAY INVISIBLE (2185 4535);
FORCEPROP 1 LAST HDL_POWER P12V_NVDIMM_DEF
J 1
(2175 4625);
DISPLAY 0.872340 (2175 4625);
PAINT GREEN (2175 4625);
DISPLAY INVISIBLE (2175 4625);
FORCEPROP 1 LAST BODY_TYPE PLUMBING
J 0
(2130 4532);
DISPLAY 0.340426 (2130 4532);
PAINT GREEN (2130 4532);
DISPLAY INVISIBLE (2130 4532);
FORCEPROP 2 LAST CDS_LIB mstr_symbols
J 0
(2175 4575);
PAINT ORANGE (2175 4575);
DISPLAY INVISIBLE (2175 4575);
FORCEPROP 1 LAST VOLTAGE 12.0
J 0
(2130 4532);
DISPLAY 0.340426 (2130 4532);
PAINT SKYBLUE (2130 4532);
DISPLAY INVISIBLE (2130 4532);
FORCEPROP 1 LAST PATH I89
J 0
(2225 4600);
DISPLAY 0.872340 (2225 4600);
PAINT AQUA (2225 4600);
DISPLAY INVISIBLE (2225 4600);
FORCEADD P12V_STBY..1
(-4525 4950);
FORCEPROP 3 LASTPIN (-4525 4900) SIG_NAME P12V_STBY\g
J 0
(-4515 4910);
DISPLAY 0.659574 (-4515 4910);
PAINT MONO (-4515 4910);
DISPLAY INVISIBLE (-4515 4910);
FORCEPROP 1 LAST HDL_POWER P12V_STBY
J 0
(-4825 4825);
DISPLAY 0.872340 (-4825 4825);
PAINT ORANGE (-4825 4825);
DISPLAY INVISIBLE (-4825 4825);
FORCEPROP 1 LAST BODY_TYPE PLUMBING
J 0
(-4570 4907);
DISPLAY 0.340426 (-4570 4907);
PAINT GREEN (-4570 4907);
DISPLAY INVISIBLE (-4570 4907);
FORCEPROP 2 LAST CDS_LIB mstr_symbols
J 0
(-4525 4950);
PAINT ORANGE (-4525 4950);
DISPLAY INVISIBLE (-4525 4950);
FORCEPROP 1 LAST SIZE 1B
J 0
(-4480 4972);
DISPLAY 0.340426 (-4480 4972);
PAINT GREEN (-4480 4972);
DISPLAY INVISIBLE (-4480 4972);
FORCEPROP 1 LAST VOLTAGE 12.0V
J 0
(-4570 4907);
DISPLAY 0.340426 (-4570 4907);
PAINT SKYBLUE (-4570 4907);
DISPLAY INVISIBLE (-4570 4907);
FORCEPROP 1 LAST PATH I9
J 0
(-4480 4952);
DISPLAY 0.340426 (-4480 4952);
PAINT GREEN (-4480 4952);
DISPLAY INVISIBLE (-4480 4952);
FORCEADD P12V_NVDIMM_ABC..1
(-2675 4950);
FORCEPROP 3 LASTPIN (-2675 4900) SIG_NAME P12V_NVDIMM_ABC\g
J 0
(-2665 4910);
DISPLAY 0.659574 (-2665 4910);
PAINT MONO (-2665 4910);
DISPLAY INVISIBLE (-2665 4910);
FORCEPROP 1 LAST HDL_POWER P12V_NVDIMM_ABC
J 1
(-2675 4975);
DISPLAY 0.872340 (-2675 4975);
PAINT GREEN (-2675 4975);
DISPLAY INVISIBLE (-2675 4975);
FORCEPROP 1 LAST BODY_TYPE PLUMBING
J 0
(-2720 4907);
DISPLAY 0.340426 (-2720 4907);
PAINT GREEN (-2720 4907);
DISPLAY INVISIBLE (-2720 4907);
FORCEPROP 2 LAST CDS_LIB mstr_symbols
J 0
(-2675 4950);
PAINT ORANGE (-2675 4950);
DISPLAY INVISIBLE (-2675 4950);
FORCEPROP 1 LAST VOLTAGE 12.0
J 0
(-2720 4907);
DISPLAY 0.340426 (-2720 4907);
PAINT SKYBLUE (-2720 4907);
DISPLAY INVISIBLE (-2720 4907);
FORCEPROP 1 LAST PATH I90
J 0
(-2625 4975);
DISPLAY 0.872340 (-2625 4975);
PAINT AQUA (-2625 4975);
DISPLAY INVISIBLE (-2625 4975);
FORCEADD BSL308C-H6327-GP..1
(-700 4100);
FORCEPROP 2 LASTPIN (-425 4300) $PN 6
J 0
(-415 4310);
DISPLAY 0.808511 (-415 4310);
PAINT ORANGE (-415 4310);
FORCEPROP 1 LAST LOCATION Q12W3
J 0
(-825 4375);
DISPLAY 0.617021 (-825 4375);
PAINT GREEN (-825 4375);
FORCEPROP 2 LASTPIN (-975 4100) $PN 2
J 2
(-985 4110);
DISPLAY 0.808511 (-985 4110);
PAINT ORANGE (-985 4110);
FORCEPROP 1 LAST VALUE BSL308C-H6327-GP
J 0
(-825 3800);
DISPLAY 0.617021 (-825 3800);
PAINT GREEN (-825 3800);
FORCEPROP 2 LASTPIN (-425 3900) $PN 4
J 0
(-415 3910);
DISPLAY 0.808511 (-415 3910);
PAINT ORANGE (-415 3910);
FORCEPROP 2 LASTPIN (-975 3900) $PN 3
J 2
(-985 3910);
DISPLAY 0.808511 (-985 3910);
PAINT ORANGE (-985 3910);
FORCEPROP 2 LASTPIN (-425 4100) $PN 5
J 0
(-415 4110);
DISPLAY 0.808511 (-415 4110);
PAINT ORANGE (-415 4110);
FORCEPROP 2 LASTPIN (-975 4300) $PN 1
J 2
(-985 4310);
DISPLAY 0.808511 (-985 4310);
PAINT ORANGE (-985 4310);
FORCEPROP 1 LAST PACK_TYPE DISCRET-GB1
J 0
(-700 4100);
DISPLAY 0.617021 (-700 4100);
PAINT GREEN (-700 4100);
DISPLAY INVISIBLE (-700 4100);
FORCEPROP 2 LAST SEC 1
J 0
(-825 4425);
DISPLAY 0.680851 (-825 4425);
PAINT MONO (-825 4425);
DISPLAY INVISIBLE (-825 4425);
FORCEPROP 2 LAST SEC_TYPE DISCRET-GB1
J 0
(-825 4425);
DISPLAY 1.021277 (-825 4425);
PAINT ORANGE (-825 4425);
DISPLAY INVISIBLE (-825 4425);
FORCEPROP 1 LAST CDS_LMAN_SYM_OUTLINE -125,250,125,-250
J 0
(-700 4100);
DISPLAY 0.468085 (-700 4100);
PAINT GREEN (-700 4100);
DISPLAY INVISIBLE (-700 4100);
FORCEPROP 2 LAST CDS_LIB w_hdl
J 0
(-700 4100);
PAINT MONO (-700 4100);
DISPLAY INVISIBLE (-700 4100);
FORCEPROP 1 LAST PART_NUMBER 075.00308.007C
J 0
(-700 4100);
DISPLAY 0.617021 (-700 4100);
PAINT GREEN (-700 4100);
DISPLAY INVISIBLE (-700 4100);
FORCEPROP 0 LAST CDS_LOCATION Q12W3
J 0
(-825 4425);
PAINT MONO (-825 4425);
DISPLAY INVISIBLE (-825 4425);
FORCEPROP 0 LAST CDS_SEC 1
J 0
(-825 4425);
PAINT MONO (-825 4425);
DISPLAY INVISIBLE (-825 4425);
FORCEPROP 1 LAST PATH I91
J 0
(-700 4100);
DISPLAY 0.617021 (-700 4100);
PAINT GREEN (-700 4100);
DISPLAY INVISIBLE (-700 4100);
FORCEADD P12V_NVDIMM_ABC..1
(1325 3350);
FORCEPROP 3 LASTPIN (1325 3300) SIG_NAME P12V_NVDIMM_ABC\g
J 0
(1335 3310);
DISPLAY 0.659574 (1335 3310);
PAINT MONO (1335 3310);
DISPLAY INVISIBLE (1335 3310);
FORCEPROP 1 LAST HDL_POWER P12V_NVDIMM_ABC
J 1
(1325 3375);
DISPLAY 0.872340 (1325 3375);
PAINT GREEN (1325 3375);
DISPLAY INVISIBLE (1325 3375);
FORCEPROP 1 LAST BODY_TYPE PLUMBING
J 0
(1280 3307);
DISPLAY 0.340426 (1280 3307);
PAINT GREEN (1280 3307);
DISPLAY INVISIBLE (1280 3307);
FORCEPROP 2 LAST CDS_LIB mstr_symbols
J 0
(1325 3350);
PAINT ORANGE (1325 3350);
DISPLAY INVISIBLE (1325 3350);
FORCEPROP 1 LAST VOLTAGE 12.0
J 0
(1280 3307);
DISPLAY 0.340426 (1280 3307);
PAINT SKYBLUE (1280 3307);
DISPLAY INVISIBLE (1280 3307);
FORCEPROP 1 LAST PATH I92
J 0
(1375 3375);
DISPLAY 0.872340 (1375 3375);
PAINT AQUA (1375 3375);
DISPLAY INVISIBLE (1375 3375);
FORCEADD CAD_NOTE..1
(50 750);
FORCEPROP 2 LAST L1 PLACE AT THE CENTER OF EACH DIMM CHANNEL. CLOSE TO THE 12V PINS OF NVDIMM CONNECTOR
J 0
(-100 625);
DISPLAY 0.829787 (-100 625);
PAINT WHITE (-100 625);
FORCEPROP 1 LAST COMMENT_BODY TRUE
J 0
(75 850);
DISPLAY 1.319149 (75 850);
PAINT ORANGE (75 850);
DISPLAY INVISIBLE (75 850);
FORCEPROP 2 LAST CDS_LIB mstr_symbols
J 0
(50 750);
PAINT MONO (50 750);
DISPLAY INVISIBLE (50 750);
FORCEADD INTEL_CORP_BPAGE..1
(3125 150);
FORCEPROP 1 LAST CDS_CON_LAST_MODIFIED Fri Jun 16 17:49:12 2017
J 0
(1700 475);
PAINT ORANGE (1700 475);
DISPLAY INVISIBLE (1700 475);
FORCEPROP 1 LAST CUSTOM_TXT_CDS <CURRENT_DESIGN_SHEET> OF <TOTAL_DESIGN_SHEETS>
J 0
(2625 175);
PAINT ORANGE (2625 175);
FORCEPROP 1 LAST CUSTOM_TXT_CDS <CON_LAST_MODIFIED>
J 0
(-875 250);
PAINT ORANGE (-875 250);
FORCEPROP 2 LAST CUSTOM_TXT_CDS <XR_PAGE_TITLE>
J 0
(-4765 5400);
DISPLAY 0.638298 (-4765 5400);
PAINT PINK (-4765 5400);
DISPLAY INVISIBLE (-4765 5400);
FORCEPROP 1 LAST SCH_TITLE POWER MISC: RAPL RESISTOR
J 0
(-4825 200);
DISPLAY 1.212766 (-4825 200);
PAINT ORANGE (-4825 200);
FORCEPROP 1 LAST COMMENT_BODY TRUE
J 0
(3137 162);
DISPLAY 0.468085 (3137 162);
PAINT GREEN (3137 162);
DISPLAY INVISIBLE (3137 162);
FORCEPROP 2 LAST CDS_LIB mstr_symbols
J 0
(3125 150);
PAINT MONO (3125 150);
DISPLAY INVISIBLE (3125 150);
FORCEPROP 2 LAST PAGE_BORDER TRUE
J 0
(-4765 5400);
DISPLAY 0.851064 (-4765 5400);
PAINT PINK (-4765 5400);
DISPLAY INVISIBLE (-4765 5400);
FORCEPROP 2 LAST CDS_XR_PAGE_TITLE CR-197 : @BASEBOARD_FAB2_LIB.BASEBOARD_FAB2(SCH_1):PAGE197
J 0
(-4765 5400);
DISPLAY 0.638298 (-4765 5400);
PAINT PINK (-4765 5400);
DISPLAY INVISIBLE (-4765 5400);
WIRE 16 -1 (-4525 2800)(-4525 2700);
WIRE 16 -1 (-4525 2700)(-4475 2700);
WIRE 16 -1 (-4475 2700)(-4475 2450);
WIRE 16 -1 (-4375 2700)(-4475 2700);
WIRE 16 -1 (-4475 2450)(-4375 2450);
WIRE 16 -1 (-4475 2150)(-4475 2450);
WIRE 16 -1 (-2925 2000)(-2925 1950);
WIRE 16 -1 (-2975 2000)(-2925 2000);
WIRE 16 -1 (-2675 2700)(-2675 2800);
WIRE 16 -1 (-2675 2700)(-2725 2700);
WIRE 16 -1 (-2725 2700)(-3625 2700);
WIRE 16 -1 (-2725 2500)(-2725 2700);
WIRE 16 -1 (-3625 2000)(-3625 2700);
WIRE 16 -1 (-4175 2700)(-3625 2700);
WIRE 16 -1 (-3525 2000)(-3625 2000);
WIRE 16 -1 (-1975 2800)(-1975 2700);
WIRE 16 -1 (-1975 2700)(-1925 2700);
WIRE 16 -1 (-1925 2700)(-1925 2450);
WIRE 16 -1 (-1825 2700)(-1925 2700);
WIRE 16 -1 (-1925 2450)(-1825 2450);
WIRE 16 -1 (-1925 2150)(-1925 2450);
WIRE 16 -1 (-375 2000)(-375 1950);
WIRE 16 -1 (-425 2000)(-375 2000);
WIRE 16 -1 (-125 2700)(-125 2800);
WIRE 16 -1 (-125 2700)(-175 2700);
WIRE 16 -1 (-175 2700)(-1075 2700);
WIRE 16 -1 (-175 2500)(-175 2700);
WIRE 16 -1 (-1075 2000)(-1075 2700);
WIRE 16 -1 (-1625 2700)(-1075 2700);
WIRE 16 -1 (-975 2000)(-1075 2000);
WIRE 16 -1 (-2925 4100)(-2925 4050);
WIRE 16 -1 (-2975 4100)(-2925 4100);
WIRE 16 -1 (-1975 4900)(-1975 4800);
WIRE 16 -1 (-1975 4800)(-1925 4800);
WIRE 16 -1 (-1925 4800)(-1925 4550);
WIRE 16 -1 (-1825 4800)(-1925 4800);
WIRE 16 -1 (-1825 4550)(-1925 4550);
WIRE 16 -1 (-1925 4250)(-1925 4550);
WIRE 16 -1 (-375 4100)(-375 4050);
WIRE 16 -1 (-425 4100)(-375 4100);
WIRE 16 -1 (-125 4800)(-125 4900);
WIRE 16 -1 (-125 4800)(-175 4800);
WIRE 16 -1 (-175 4800)(-1075 4800);
WIRE 16 -1 (-175 4600)(-175 4800);
WIRE 16 -1 (-1075 4100)(-1075 4800);
WIRE 16 -1 (-1625 4800)(-1075 4800);
WIRE 16 -1 (-975 4100)(-1075 4100);
WIRE 16 -1 (1325 1150)(1325 1175);
WIRE 16 -1 (1325 1400)(1325 1375);
WIRE 16 -1 (1325 1725)(1325 1750);
WIRE 16 -1 (2175 1125)(2175 1175);
WIRE 16 -1 (2175 1400)(2175 1375);
WIRE 16 -1 (2175 1700)(2175 1750);
WIRE 16 -1 (1325 1975)(1325 1950);
WIRE 16 -1 (1325 2375)(1325 2400);
WIRE 16 -1 (1325 2625)(1325 2600);
WIRE 16 -1 (1325 3025)(1325 3075);
WIRE 16 -1 (1325 3600)(1325 3650);
WIRE 16 -1 (2175 1975)(2175 1950);
WIRE 16 -1 (2175 2350)(2175 2400);
WIRE 16 -1 (2175 2625)(2175 2600);
WIRE 16 -1 (2175 3025)(2175 3075);
WIRE 16 -1 (2175 3300)(2175 3275);
WIRE 16 -1 (2175 3600)(2175 3650);
WIRE 16 -1 (1325 3875)(1325 3850);
WIRE 16 -1 (1325 4250)(1325 4300);
WIRE 16 -1 (1325 4525)(1325 4500);
WIRE 16 -1 (2175 3875)(2175 3850);
WIRE 16 -1 (2175 4250)(2175 4300);
WIRE 16 -1 (2175 4525)(2175 4500);
WIRE 16 -1 (-4525 4900)(-4525 4800);
WIRE 16 -1 (-4525 4800)(-4475 4800);
WIRE 16 -1 (-4475 4800)(-4475 4550);
WIRE 16 -1 (-4375 4800)(-4475 4800);
WIRE 16 -1 (-4475 4250)(-4475 4550);
WIRE 16 -1 (-4475 4550)(-4375 4550);
WIRE 16 -1 (-2675 4800)(-2675 4900);
WIRE 16 -1 (-2675 4800)(-2725 4800);
WIRE 16 -1 (-2725 4800)(-3625 4800);
WIRE 16 -1 (-2725 4600)(-2725 4800);
WIRE 16 -1 (-3625 4100)(-3625 4800);
WIRE 16 -1 (-4175 4800)(-3625 4800);
WIRE 16 -1 (-3525 4100)(-3625 4100);
WIRE 16 -1 (1325 3300)(1325 3275);
WIRE 3 682 (-3725 3950)(-4575 3950);
WIRE 3 682 (-3725 4300)(-3725 3950);
WIRE 3 682 (-4575 3950)(-4575 4300);
WIRE 3 682 (-4575 4300)(-3725 4300);
WIRE 16 -1 (-3625 3900)(-3525 3900);
WIRE 16 -1 (-3625 3650)(-3625 3900);
WIRE 16 -1 (-2725 3650)(-3625 3650);
FORCEPROP 2 LAST SIG_NAME PWRGD_PVDDQ_ABC_N
J 0
(-3565 3665);
DISPLAY 0.617021 (-3565 3665);
PAINT ORANGE (-3565 3665);
FORCEPROP 2 LASTPROP $XRERR UNIQUE?
J 0
(-3805 3665);
DISPLAY 0.638298 (-3805 3665);
PAINT MONO (-3805 3665);
DISPLAY INVISIBLE (-3805 3665);
WIRE 16 -1 (-2725 4300)(-2725 3650);
WIRE 16 -1 (-2975 4300)(-2725 4300);
WIRE 16 -1 (-2725 4300)(-2725 4400);
WIRE 16 -1 (-2975 3900)(-2825 3900);
WIRE 16 -1 (-4025 4550)(-4125 4550);
WIRE 16 -1 (-4025 4250)(-4025 4550);
WIRE 16 -1 (-2825 3900)(-2825 4550);
WIRE 16 -1 (-2825 4550)(-4025 4550);
FORCEPROP 2 LAST SIG_NAME P12V_NVDIMM_ABC_D
J 0
(-3560 4560);
DISPLAY 0.638298 (-3560 4560);
PAINT ORANGE (-3560 4560);
FORCEPROP 2 LASTPROP $XRERR UNIQUE?
J 0
(-3800 4560);
DISPLAY 0.638298 (-3800 4560);
PAINT MONO (-3800 4560);
DISPLAY INVISIBLE (-3800 4560);
WIRE 3 682 (-4775 5100)(-4775 850);
WIRE 3 682 (425 5100)(-4775 5100);
WIRE 3 682 (-4775 850)(425 850);
WIRE 3 682 (425 850)(425 5100);
WIRE 16 -1 (-4125 3800)(-4025 3800);
WIRE 16 -1 (-4025 4000)(-4025 3800);
WIRE 16 -1 (-4175 3550)(-4025 3550);
WIRE 16 -1 (-4025 3550)(-4025 3800);
WIRE 16 -1 (-4025 3550)(-4025 3300);
WIRE 16 -1 (-4025 3300)(-2875 3300);
FORCEPROP 2 LAST SIG_NAME VR_PVDDQ_ABC_VINSEN
J 0
(-3915 3315);
DISPLAY 0.617021 (-3915 3315);
PAINT ORANGE (-3915 3315);
WIRE 16 -1 (-4475 3800)(-4375 3800);
WIRE 16 -1 (-4475 4000)(-4475 3800);
WIRE 16 -1 (-4375 3550)(-4475 3550);
WIRE 16 -1 (-4475 3550)(-4475 3800);
WIRE 16 -1 (-4475 3250)(-4475 3550);
WIRE 16 -1 (-4475 3250)(-2875 3250);
FORCEPROP 2 LAST SIG_NAME VR_PVDDQ_ABC_AIINSEN
J 0
(-3910 3260);
DISPLAY 0.617021 (-3910 3260);
PAINT ORANGE (-3910 3260);
WIRE 16 -1 (-1475 3300)(-325 3300);
FORCEPROP 2 LAST SIG_NAME VR_PVDDQ_GHJ_VINSEN
J 0
(-1365 3315);
DISPLAY 0.617021 (-1365 3315);
PAINT ORANGE (-1365 3315);
WIRE 16 -1 (-1625 3550)(-1475 3550);
WIRE 16 -1 (-1475 3550)(-1475 3300);
WIRE 16 -1 (-1575 3800)(-1475 3800);
WIRE 16 -1 (-1475 3800)(-1475 3550);
WIRE 16 -1 (-1475 4000)(-1475 3800);
WIRE 3 682 (-1175 3950)(-2025 3950);
WIRE 3 682 (-1175 4300)(-1175 3950);
WIRE 3 682 (-2025 3950)(-2025 4300);
WIRE 3 682 (-2025 4300)(-1175 4300);
WIRE 68 -1 (-1425 3500)(-1375 3500);
WIRE 68 -1 (-2025 3600)(-1425 3600);
WIRE 68 -1 (-1425 3600)(-1425 3500);
WIRE 68 -1 (-2025 3900)(-2025 3600);
WIRE 68 -1 (-1375 3900)(-2025 3900);
WIRE 68 -1 (-1425 3600)(-1375 3600);
WIRE 68 -1 (-1375 3600)(-1375 3900);
WIRE 16 -1 (-1825 3800)(-1925 3800);
WIRE 16 -1 (-1925 4000)(-1925 3800);
WIRE 16 -1 (-1825 3550)(-1925 3550);
WIRE 16 -1 (-1925 3800)(-1925 3550);
WIRE 16 -1 (-1925 3250)(-1925 3550);
WIRE 16 -1 (-1925 3250)(-325 3250);
FORCEPROP 2 LAST SIG_NAME VR_PVDDQ_GHJ_AIINSEN
J 0
(-1360 3260);
DISPLAY 0.617021 (-1360 3260);
PAINT ORANGE (-1360 3260);
WIRE 16 -1 (-2975 1800)(-2825 1800);
WIRE 16 -1 (-4125 2450)(-4025 2450);
WIRE 16 -1 (-4025 2450)(-4025 2150);
WIRE 16 -1 (-2825 1800)(-2825 2450);
WIRE 16 -1 (-2825 2450)(-4025 2450);
FORCEPROP 2 LAST SIG_NAME P12V_NVDIMM_DEF_D
J 0
(-3560 2460);
DISPLAY 0.638298 (-3560 2460);
PAINT ORANGE (-3560 2460);
FORCEPROP 2 LASTPROP $XRERR UNIQUE?
J 0
(-3800 2460);
DISPLAY 0.638298 (-3800 2460);
PAINT MONO (-3800 2460);
DISPLAY INVISIBLE (-3800 2460);
WIRE 16 -1 (-425 3900)(-275 3900);
WIRE 16 -1 (-1475 4550)(-1575 4550);
WIRE 16 -1 (-1475 4550)(-1475 4250);
WIRE 16 -1 (-275 3900)(-275 4550);
WIRE 16 -1 (-275 4550)(-1475 4550);
FORCEPROP 2 LAST SIG_NAME P12V_NVDIMM_GHJ_D
J 0
(-1010 4560);
DISPLAY 0.638298 (-1010 4560);
PAINT ORANGE (-1010 4560);
FORCEPROP 2 LASTPROP $XRERR UNIQUE?
J 0
(-1250 4560);
DISPLAY 0.638298 (-1250 4560);
PAINT MONO (-1250 4560);
DISPLAY INVISIBLE (-1250 4560);
WIRE 16 -1 (-3675 3600)(-2875 3600);
FORCEPROP 2 LAST SIG_NAME PWRGD_PVDDQ_ABC
J 0
(-3560 3610);
DISPLAY 0.638298 (-3560 3610);
PAINT ORANGE (-3560 3610);
WIRE 16 -1 (-3675 4300)(-3675 3600);
WIRE 16 -1 (-3675 4300)(-3525 4300);
WIRE 68 -1 (975 4700)(2775 4700);
WIRE 68 -1 (2775 4700)(2775 1000);
WIRE 68 -1 (2775 1000)(975 1000);
WIRE 68 -1 (975 4700)(975 1000);
WIRE 68 -1 (975 750)(975 1000);
WIRE 68 -1 (250 750)(975 750);
WIRE 16 -1 (-1125 4300)(-975 4300);
WIRE 16 -1 (-1125 4300)(-1125 3600);
WIRE 16 -1 (-325 3600)(-1125 3600);
FORCEPROP 2 LAST SIG_NAME PWRGD_PVDDQ_GHJ
J 0
(-1015 3615);
DISPLAY 0.617021 (-1015 3615);
PAINT ORANGE (-1015 3615);
WIRE 16 -1 (-1075 3900)(-975 3900);
WIRE 16 -1 (-1075 3650)(-1075 3900);
WIRE 16 -1 (-175 3650)(-1075 3650);
FORCEPROP 2 LAST SIG_NAME PWRGD_PVDDQ_GHJ_N
J 0
(-1015 3665);
DISPLAY 0.617021 (-1015 3665);
PAINT ORANGE (-1015 3665);
FORCEPROP 2 LASTPROP $XRERR UNIQUE?
J 0
(-1255 3665);
DISPLAY 0.638298 (-1255 3665);
PAINT MONO (-1255 3665);
DISPLAY INVISIBLE (-1255 3665);
WIRE 16 -1 (-175 4300)(-175 3650);
WIRE 16 -1 (-425 4300)(-175 4300);
WIRE 16 -1 (-175 4300)(-175 4400);
WIRE 68 -1 (-3975 1400)(-3925 1400);
WIRE 68 -1 (-4575 1500)(-3975 1500);
WIRE 68 -1 (-3975 1500)(-3975 1400);
WIRE 68 -1 (-4575 1800)(-4575 1500);
WIRE 68 -1 (-3925 1800)(-4575 1800);
WIRE 68 -1 (-3975 1500)(-3925 1500);
WIRE 68 -1 (-3925 1500)(-3925 1800);
WIRE 16 -1 (-1075 1800)(-975 1800);
WIRE 16 -1 (-1075 1550)(-1075 1800);
WIRE 16 -1 (-175 1550)(-1075 1550);
FORCEPROP 2 LAST SIG_NAME PWRGD_PVDDQ_KLM_N
J 0
(-1015 1565);
DISPLAY 0.617021 (-1015 1565);
PAINT ORANGE (-1015 1565);
FORCEPROP 2 LASTPROP $XRERR UNIQUE?
J 0
(-1255 1565);
DISPLAY 0.638298 (-1255 1565);
PAINT MONO (-1255 1565);
DISPLAY INVISIBLE (-1255 1565);
WIRE 16 -1 (-175 2200)(-175 1550);
WIRE 16 -1 (-425 2200)(-175 2200);
WIRE 16 -1 (-175 2200)(-175 2300);
WIRE 16 -1 (-3625 1800)(-3525 1800);
WIRE 16 -1 (-3625 1550)(-3625 1800);
WIRE 16 -1 (-2725 1550)(-3625 1550);
FORCEPROP 2 LAST SIG_NAME PWRGD_PVDDQ_DEF_N
J 0
(-3565 1565);
DISPLAY 0.617021 (-3565 1565);
PAINT ORANGE (-3565 1565);
FORCEPROP 2 LASTPROP $XRERR UNIQUE?
J 0
(-3805 1565);
DISPLAY 0.638298 (-3805 1565);
PAINT MONO (-3805 1565);
DISPLAY INVISIBLE (-3805 1565);
WIRE 16 -1 (-2725 2200)(-2725 1550);
WIRE 16 -1 (-2975 2200)(-2725 2200);
WIRE 16 -1 (-2725 2200)(-2725 2300);
WIRE 16 -1 (-1125 1500)(-325 1500);
FORCEPROP 2 LAST SIG_NAME PWRGD_PVDDQ_KLM
J 0
(-1015 1515);
DISPLAY 0.617021 (-1015 1515);
PAINT ORANGE (-1015 1515);
WIRE 16 -1 (-1125 2200)(-1125 1500);
WIRE 16 -1 (-1125 2200)(-975 2200);
WIRE 68 -1 (-3975 3500)(-3925 3500);
WIRE 68 -1 (-4575 3900)(-4575 3600);
WIRE 68 -1 (-3925 3900)(-4575 3900);
WIRE 68 -1 (-3925 3600)(-3925 3900);
WIRE 68 -1 (-4575 3600)(-3975 3600);
WIRE 68 -1 (-3975 3600)(-3975 3500);
WIRE 68 -1 (-3975 3600)(-3925 3600);
WIRE 16 -1 (-4025 1200)(-2875 1200);
FORCEPROP 2 LAST SIG_NAME VR_PVDDQ_DEF_VINSEN
J 0
(-3915 1215);
DISPLAY 0.617021 (-3915 1215);
PAINT ORANGE (-3915 1215);
WIRE 16 -1 (-4175 1450)(-4025 1450);
WIRE 16 -1 (-4025 1450)(-4025 1200);
WIRE 16 -1 (-4125 1700)(-4025 1700);
WIRE 16 -1 (-4025 1700)(-4025 1450);
WIRE 16 -1 (-4025 1900)(-4025 1700);
WIRE 16 -1 (-4475 1700)(-4375 1700);
WIRE 16 -1 (-4475 1900)(-4475 1700);
WIRE 16 -1 (-4375 1450)(-4475 1450);
WIRE 16 -1 (-4475 1700)(-4475 1450);
WIRE 16 -1 (-4475 1150)(-4475 1450);
WIRE 16 -1 (-4475 1150)(-2875 1150);
FORCEPROP 2 LAST SIG_NAME VR_PVDDQ_DEF_AIINSEN
J 0
(-3910 1160);
DISPLAY 0.617021 (-3910 1160);
PAINT ORANGE (-3910 1160);
WIRE 16 -1 (-3675 1500)(-2875 1500);
FORCEPROP 2 LAST SIG_NAME PWRGD_PVDDQ_DEF
J 0
(-3565 1515);
DISPLAY 0.617021 (-3565 1515);
PAINT ORANGE (-3565 1515);
WIRE 16 -1 (-3675 2200)(-3675 1500);
WIRE 16 -1 (-3675 2200)(-3525 2200);
WIRE 3 682 (-4575 1850)(-4575 2200);
WIRE 3 682 (-3725 1850)(-4575 1850);
WIRE 3 682 (-4575 2200)(-3725 2200);
WIRE 3 682 (-3725 2200)(-3725 1850);
WIRE 68 -1 (-1425 1400)(-1375 1400);
WIRE 68 -1 (-1425 1500)(-1425 1400);
WIRE 68 -1 (-2025 1500)(-1425 1500);
WIRE 68 -1 (-1425 1500)(-1375 1500);
WIRE 68 -1 (-1375 1500)(-1375 1800);
WIRE 68 -1 (-2025 1800)(-2025 1500);
WIRE 68 -1 (-2025 1800)(-1375 1800);
WIRE 16 -1 (-1925 1700)(-1825 1700);
WIRE 16 -1 (-1925 1900)(-1925 1700);
WIRE 16 -1 (-1825 1450)(-1925 1450);
WIRE 16 -1 (-1925 1700)(-1925 1450);
WIRE 16 -1 (-1925 1150)(-1925 1450);
WIRE 16 -1 (-1925 1150)(-325 1150);
FORCEPROP 2 LAST SIG_NAME VR_PVDDQ_KLM_AIINSEN
J 0
(-1360 1160);
DISPLAY 0.617021 (-1360 1160);
PAINT ORANGE (-1360 1160);
WIRE 16 -1 (-1475 1200)(-325 1200);
FORCEPROP 2 LAST SIG_NAME VR_PVDDQ_KLM_VINSEN
J 0
(-1365 1215);
DISPLAY 0.617021 (-1365 1215);
PAINT ORANGE (-1365 1215);
WIRE 16 -1 (-1625 1450)(-1475 1450);
WIRE 16 -1 (-1475 1450)(-1475 1200);
WIRE 16 -1 (-1575 1700)(-1475 1700);
WIRE 16 -1 (-1475 1700)(-1475 1450);
WIRE 16 -1 (-1475 1900)(-1475 1700);
WIRE 16 -1 (-425 1800)(-275 1800);
WIRE 16 -1 (-1475 2450)(-1575 2450);
WIRE 16 -1 (-1475 2150)(-1475 2450);
WIRE 16 -1 (-275 1800)(-275 2450);
WIRE 16 -1 (-275 2450)(-1475 2450);
FORCEPROP 2 LAST SIG_NAME P12V_NVDIMM_KLM_D
J 0
(-1010 2460);
DISPLAY 0.638298 (-1010 2460);
PAINT ORANGE (-1010 2460);
FORCEPROP 2 LASTPROP $XRERR UNIQUE?
J 0
(-1250 2460);
DISPLAY 0.638298 (-1250 2460);
PAINT MONO (-1250 2460);
DISPLAY INVISIBLE (-1250 2460);
WIRE 3 682 (-1175 2200)(-1175 1850);
WIRE 3 682 (-2025 2200)(-1175 2200);
WIRE 3 682 (-2025 1850)(-1175 1850);
WIRE 3 682 (-2025 1850)(-2025 2200);
DOT 1 (-1925 1700);
DOT 1 (-1475 1700);
DOT 1 (-1425 1500);
DOT 1 (-1925 1450);
DOT 1 (-1475 1450);
DOT 1 (-4475 1700);
DOT 1 (-4025 1700);
DOT 1 (-4025 3800);
DOT 1 (-3975 1500);
DOT 1 (-4475 1450);
DOT 1 (-4025 1450);
DOT 1 (-4475 4550);
DOT 1 (-175 4300);
DOT 1 (-1475 4550);
DOT 1 (-1075 4800);
DOT 1 (-1925 3800);
DOT 1 (-1475 3800);
DOT 1 (-1425 3600);
DOT 1 (-1925 3550);
DOT 1 (-1475 3550);
DOT 1 (-4475 3800);
DOT 1 (-4475 3550);
DOT 1 (-4025 3550);
DOT 1 (-1075 2700);
DOT 1 (-1925 2450);
DOT 1 (-4475 2700);
DOT 1 (-175 2200);
DOT 1 (-175 2700);
DOT 1 (-175 4800);
DOT 1 (975 1000);
DOT 1 (-2725 4300);
DOT 1 (-1925 4550);
DOT 1 (-4475 4800);
DOT 1 (-1475 2450);
DOT 1 (-2725 2200);
DOT 1 (-4475 2450);
DOT 1 (-3625 2700);
DOT 1 (-3975 3600);
DOT 1 (-1925 4800);
DOT 1 (-4025 2450);
DOT 1 (-4025 4550);
DOT 1 (-3625 4800);
DOT 1 (-2725 4800);
DOT 1 (-1925 2700);
DOT 1 (-2725 2700);
FORCENOTE
RAPL RESISTOR CH ABC
(-4033 4821) 0;
DISPLAY LEFT (-4033 4821);
DISPLAY 1.723404 (-4033 4821);
PAINT PURPLE (-4033 4821);
FORCENOTE
TP FAB3-DVT CHANGE R9M4 TO 0.004OHM RES 20161121
(-1800 2950) 0;
DISPLAY LEFT (-1800 2950);
DISPLAY 0.638298 (-1800 2950);
PAINT RED (-1800 2950);
FORCENOTE
TP FAB3-DVT CHANGE R4B12 TO 0.004OHM RES 20161121
(-4350 2950) 0;
DISPLAY LEFT (-4350 2950);
DISPLAY 0.638298 (-4350 2950);
PAINT RED (-4350 2950);
FORCENOTE
TP FAB3-DVT CHANGE R1F3 TO 0.004OHM RES 20161121
(-1800 5050) 0;
DISPLAY LEFT (-1800 5050);
DISPLAY 0.638298 (-1800 5050);
PAINT RED (-1800 5050);
FORCENOTE
TP FAB3-DVT CHANGE R4F2 TO 0.004OHM RES 20161121
(-4350 5050) 0;
DISPLAY LEFT (-4350 5050);
DISPLAY 0.638298 (-4350 5050);
PAINT RED (-4350 5050);
FORCENOTE
OTHERWISE PICK A VALUE > R1
(-3875 3400) 0;
DISPLAY LEFT (-3875 3400);
DISPLAY 0.808511 (-3875 3400);
PAINT PURPLE (-3875 3400);
FORCENOTE
R12W20:
(-1325 1400) 0;
DISPLAY LEFT (-1325 1400);
DISPLAY 0.808511 (-1325 1400);
PAINT PURPLE (-1325 1400);
FORCENOTE
DNP IF LIN < 19A
(-1325 1350) 0;
DISPLAY LEFT (-1325 1350);
DISPLAY 0.808511 (-1325 1350);
PAINT PURPLE (-1325 1350);
FORCENOTE
OTHERWISE PICK A VALUE > R1
(-1325 1300) 0;
DISPLAY LEFT (-1325 1300);
DISPLAY 0.808511 (-1325 1300);
PAINT PURPLE (-1325 1300);
FORCENOTE
BASED ON IIN LEVEL, 1%, 0402
(-1325 1250) 0;
DISPLAY LEFT (-1325 1250);
DISPLAY 0.808511 (-1325 1250);
PAINT PURPLE (-1325 1250);
FORCENOTE
BOM_COST=PVDDQ_KLM_VR
(-1925 1025) 0;
DISPLAY LEFT (-1925 1025);
DISPLAY 1.574468 (-1925 1025);
PAINT PURPLE (-1925 1025);
FORCENOTE
ROOM=PVDDQ_KLM_PWR_VR
(-1925 900) 0;
DISPLAY LEFT (-1925 900);
DISPLAY 1.574468 (-1925 900);
PAINT PURPLE (-1925 900);
FORCENOTE
BASED ON IIN LEVEL, 1%, 0402
(-3875 1250) 0;
DISPLAY LEFT (-3875 1250);
DISPLAY 0.808511 (-3875 1250);
PAINT PURPLE (-3875 1250);
FORCENOTE
BOM_COST=PVDDQ_DEF_VR
(-4475 1025) 0;
DISPLAY LEFT (-4475 1025);
DISPLAY 1.574468 (-4475 1025);
PAINT PURPLE (-4475 1025);
FORCENOTE
ROOM=PVDDQ_DEF_PWR_VR
(-4475 900) 0;
DISPLAY LEFT (-4475 900);
DISPLAY 1.574468 (-4475 900);
PAINT PURPLE (-4475 900);
FORCENOTE
DNP IF LIN < 19A
(-3875 1350) 0;
DISPLAY LEFT (-3875 1350);
DISPLAY 0.808511 (-3875 1350);
PAINT PURPLE (-3875 1350);
FORCENOTE
R12W10:
(-3875 1400) 0;
DISPLAY LEFT (-3875 1400);
DISPLAY 0.808511 (-3875 1400);
PAINT PURPLE (-3875 1400);
FORCENOTE
BASED ON IIN LEVEL, 1%, 0402
(-1325 3350) 0;
DISPLAY LEFT (-1325 3350);
DISPLAY 0.808511 (-1325 3350);
PAINT PURPLE (-1325 3350);
FORCENOTE
OTHERWISE PICK A VALUE > R1
(-1325 3400) 0;
DISPLAY LEFT (-1325 3400);
DISPLAY 0.808511 (-1325 3400);
PAINT PURPLE (-1325 3400);
FORCENOTE
DNP IF LIN < 19A
(-1325 3450) 0;
DISPLAY LEFT (-1325 3450);
DISPLAY 0.808511 (-1325 3450);
PAINT PURPLE (-1325 3450);
FORCENOTE
TP FAB1 CHANGE TO INFX RECOMMENDED CIRCUIT 0122
(-4775 775) 0;
DISPLAY LEFT (-4775 775);
DISPLAY 1.021277 (-4775 775);
PAINT RED (-4775 775);
FORCENOTE
R12W5:
(-3875 3500) 0;
DISPLAY LEFT (-3875 3500);
DISPLAY 0.808511 (-3875 3500);
PAINT PURPLE (-3875 3500);
FORCENOTE
RAPL RESISTOR CH KLM
(-1483 2721) 0;
DISPLAY LEFT (-1483 2721);
DISPLAY 1.723404 (-1483 2721);
PAINT PURPLE (-1483 2721);
FORCENOTE
TP FAB1 CHANGE RES TO 064.6653F.M001 0318
(-2025 2250) 0;
DISPLAY LEFT (-2025 2250);
DISPLAY 0.638298 (-2025 2250);
PAINT RED (-2025 2250);
FORCENOTE
TP FAB1 CHANGE PACKAGE SIZE TO 0805
(-2025 2300) 0;
DISPLAY LEFT (-2025 2300);
DISPLAY 0.638298 (-2025 2300);
PAINT RED (-2025 2300);
FORCENOTE
TP FAB3 CHANGE RES TO 100K OHM 0901
(-2025 2350) 0;
DISPLAY LEFT (-2025 2350);
DISPLAY 0.638298 (-2025 2350);
PAINT RED (-2025 2350);
FORCENOTE
DNP IF LIN < 19A
(-3875 3450) 0;
DISPLAY LEFT (-3875 3450);
DISPLAY 0.808511 (-3875 3450);
PAINT PURPLE (-3875 3450);
FORCENOTE
R12W15:
(-1325 3500) 0;
DISPLAY LEFT (-1325 3500);
DISPLAY 0.808511 (-1325 3500);
PAINT PURPLE (-1325 3500);
FORCENOTE
TP FAB1 CHANGE RES TO 064.6653F.M001 0318
(-2025 4350) 0;
DISPLAY LEFT (-2025 4350);
DISPLAY 0.638298 (-2025 4350);
PAINT RED (-2025 4350);
FORCENOTE
TP FAB1 CHANGE PACKAGE SIZE TO 0805
(-2025 4400) 0;
DISPLAY LEFT (-2025 4400);
DISPLAY 0.638298 (-2025 4400);
PAINT RED (-2025 4400);
FORCENOTE
TP FAB3 CHANGE RES TO 100K OHM 0901
(-2025 4450) 0;
DISPLAY LEFT (-2025 4450);
DISPLAY 0.638298 (-2025 4450);
PAINT RED (-2025 4450);
FORCENOTE
RAPL RESISTOR CH GHJ
(-1483 4821) 0;
DISPLAY LEFT (-1483 4821);
DISPLAY 1.723404 (-1483 4821);
PAINT PURPLE (-1483 4821);
FORCENOTE
TP FAB1 CHANGE RES TO 064.6653F.M001 0318
(-4575 2250) 0;
DISPLAY LEFT (-4575 2250);
DISPLAY 0.638298 (-4575 2250);
PAINT RED (-4575 2250);
FORCENOTE
TP FAB1 CHANGE PACKAGE SIZE TO 0805
(-4575 2300) 0;
DISPLAY LEFT (-4575 2300);
DISPLAY 0.638298 (-4575 2300);
PAINT RED (-4575 2300);
FORCENOTE
TP FAB3 CHANGE RES TO 100K OHM 0901
(-4575 2350) 0;
DISPLAY LEFT (-4575 2350);
DISPLAY 0.638298 (-4575 2350);
PAINT RED (-4575 2350);
FORCENOTE
ROOM=PVDDQ_GHJ_PWR_VR
(-1925 3025) 0;
DISPLAY LEFT (-1925 3025);
DISPLAY 1.574468 (-1925 3025);
PAINT PURPLE (-1925 3025);
FORCENOTE
BOM_COST=PVDDQ_GHJ_VR
(-1925 3125) 0;
DISPLAY LEFT (-1925 3125);
DISPLAY 1.574468 (-1925 3125);
PAINT PURPLE (-1925 3125);
FORCENOTE
RAPL RESISTOR CH DEF
(-4008 2721) 0;
DISPLAY LEFT (-4008 2721);
DISPLAY 1.723404 (-4008 2721);
PAINT PURPLE (-4008 2721);
FORCENOTE
ROOM=PVDDQ_ABC_PWR_VR
(-4475 3025) 0;
DISPLAY LEFT (-4475 3025);
DISPLAY 1.574468 (-4475 3025);
PAINT PURPLE (-4475 3025);
FORCENOTE
BOM_COST=PVDDQ_ABC_VR
(-4475 3125) 0;
DISPLAY LEFT (-4475 3125);
DISPLAY 1.574468 (-4475 3125);
PAINT PURPLE (-4475 3125);
FORCENOTE
BASED ON IIN LEVEL, 1%, 0402
(-3875 3350) 0;
DISPLAY LEFT (-3875 3350);
DISPLAY 0.808511 (-3875 3350);
PAINT PURPLE (-3875 3350);
FORCENOTE
TP FAB1 CHANGE PACKAGE SIZE TO 0805
(-4575 4400) 0;
DISPLAY LEFT (-4575 4400);
DISPLAY 0.638298 (-4575 4400);
PAINT RED (-4575 4400);
FORCENOTE
OTHERWISE PICK A VALUE > R1
(-3875 1300) 0;
DISPLAY LEFT (-3875 1300);
DISPLAY 0.808511 (-3875 1300);
PAINT PURPLE (-3875 1300);
FORCENOTE
TP FAB3 CHANGE RES TO 100K OHM 0901
(-4575 4450) 0;
DISPLAY LEFT (-4575 4450);
DISPLAY 0.638298 (-4575 4450);
PAINT RED (-4575 4450);
FORCENOTE
TP FAB1 CHANGE RES TO 064.6653F.M001 0318
(-4575 4350) 0;
DISPLAY LEFT (-4575 4350);
DISPLAY 0.638298 (-4575 4350);
PAINT RED (-4575 4350);
QUIT
